FILE_TYPE = MACRO_DRAWING;
SET COLOR_WIRE YELLOW;
SET COLOR_PROP ORANGE;
SET COLOR_DOT WHITE;
SET COLOR_ARC YELLOW;
SET COLOR_BODY GREEN;
SET COLOR_NOTE PURPLE;
SET PROP_DISPLAY VALUE;
SET PAGE_NUMBER P156;
FORCEADD OFFPAGE..1
(4400 1100);
FORCEPROP 2 LAST $XR0 164 
J 0
(4148 1100);
DISPLAY 0.638298 (4148 1100);
PAINT MONO (4148 1100);
FORCEPROP 1 LAST COMMENT_BODY TRUE
J 0
(4525 1000);
DISPLAY 0.872340 (4525 1000);
PAINT GREEN (4525 1000);
DISPLAY INVISIBLE (4525 1000);
FORCEPROP 1 LAST OFFPAGE TRUE
J 0
(4725 975);
DISPLAY 0.872340 (4725 975);
PAINT GREEN (4725 975);
DISPLAY INVISIBLE (4725 975);
FORCEPROP 2 LAST CDS_LIB standard
J 0
(4400 1100);
PAINT MONO (4400 1100);
DISPLAY INVISIBLE (4400 1100);
FORCEPROP 2 LAST PATH I10
J 0
(4150 1150);
DISPLAY 1.021277 (4150 1150);
DISPLAY INVISIBLE (4150 1150);
FORCEADD UNIVERSAL_GND..1
(5050 1200);
FORCEPROP 3 LASTPIN (5050 1250) SIG_NAME GND\g
J 0
(5060 1260);
DISPLAY 0.659574 (5060 1260);
PAINT MONO (5060 1260);
DISPLAY INVISIBLE (5060 1260);
FORCEPROP 1 LAST HDL_POWER GND
J 1
(5075 1125);
DISPLAY 0.872340 (5075 1125);
PAINT GREEN (5075 1125);
DISPLAY INVISIBLE (5075 1125);
FORCEPROP 2 LAST CDS_LIB logical_power
J 0
(5050 1200);
PAINT MONO (5050 1200);
DISPLAY INVISIBLE (5050 1200);
FORCEPROP 1 LAST PATH I11
J 0
(5125 1200);
DISPLAY 0.872340 (5125 1200);
PAINT AQUA (5125 1200);
DISPLAY INVISIBLE (5125 1200);
FORCEADD Q_CAP..1
R 2
(5050 1425);
FORCEPROP 1 LAST PART_NUMBER CH4104K1B00
J 2
(5000 1275);
DISPLAY 0.510638 (5000 1275);
DISPLAY INVISIBLE (5000 1275);
FORCEPROP 1 LAST VOLTAGE 25V
J 2
(5000 1425);
DISPLAY 0.510638 (5000 1425);
FORCEPROP 1 LAST PACK_TYPE 0402
J 2
(5000 1225);
DISPLAY 0.510638 (5000 1225);
FORCEPROP 1 LAST MATERIAL X7R
J 2
(5000 1325);
DISPLAY 0.510638 (5000 1325);
FORCEPROP 1 LAST TOLERANCE 10%
J 2
(5000 1375);
DISPLAY 0.510638 (5000 1375);
FORCEPROP 1 LAST VALUE 0.1UF
J 2
(5000 1475);
DISPLAY 0.510638 (5000 1475);
FORCEPROP 1 LAST $LOCATION C1821
J 2
(5000 1525);
DISPLAY 0.978723 (5000 1525);
FORCEPROP 1 LASTPIN (5050 1525) $PN 1
J 2
(5040 1505);
DISPLAY 0.787234 (5040 1505);
FORCEPROP 1 LASTPIN (5050 1325) $PN 2
J 2
(5040 1305);
DISPLAY 0.787234 (5040 1305);
FORCEPROP 2 LAST CDS_LIB pure_quanta
J 0
(5050 1425);
PAINT MONO (5050 1425);
DISPLAY INVISIBLE (5050 1425);
FORCEPROP 1 LAST PATH I12
J 2
(5000 1575);
DISPLAY 0.978723 (5000 1575);
PAINT WHITE (5000 1575);
DISPLAY INVISIBLE (5000 1575);
FORCEPROP 2 LAST CDS_LOCATION C1821
J 0
(5000 1625);
DISPLAY 1.021277 (5000 1625);
DISPLAY INVISIBLE (5000 1625);
FORCEPROP 2 LAST $SEC 1
J 0
(5000 1625);
DISPLAY 0.680851 (5000 1625);
PAINT MONO (5000 1625);
DISPLAY INVISIBLE (5000 1625);
FORCEPROP 2 LAST CDS_SEC 1
J 0
(5000 1625);
DISPLAY 1.021277 (5000 1625);
DISPLAY INVISIBLE (5000 1625);
FORCEADD UNIVERSAL_GND..1
(7650 -2100);
FORCEPROP 3 LASTPIN (7650 -2050) SIG_NAME GND\g
J 0
(7660 -2040);
DISPLAY 0.659574 (7660 -2040);
PAINT MONO (7660 -2040);
DISPLAY INVISIBLE (7660 -2040);
FORCEPROP 1 LAST PATH I19
J 0
(7725 -2100);
DISPLAY 0.872340 (7725 -2100);
PAINT AQUA (7725 -2100);
DISPLAY INVISIBLE (7725 -2100);
FORCEPROP 1 LAST HDL_POWER GND
J 1
(7675 -2175);
DISPLAY 0.872340 (7675 -2175);
PAINT GREEN (7675 -2175);
DISPLAY INVISIBLE (7675 -2175);
FORCEPROP 2 LAST CDS_LIB logical_power
J 0
(7650 -2100);
DISPLAY INVISIBLE (7650 -2100);
FORCEADD Q_RES..1
(6350 -1775);
FORCEPROP 1 LAST PART_NUMBER CS03322FB03
J 0
(6250 -1700);
DISPLAY 0.510638 (6250 -1700);
DISPLAY INVISIBLE (6250 -1700);
FORCEPROP 1 LAST VALUE 33.2
J 2
(6550 -1775);
DISPLAY 0.510638 (6550 -1775);
FORCEPROP 1 LAST TOLERANCE 1%
J 0
(6575 -1775);
DISPLAY 0.510638 (6575 -1775);
FORCEPROP 1 LAST MATERIAL CHIP
J 0
(6675 -1775);
DISPLAY 0.510638 (6675 -1775);
FORCEPROP 1 LAST WATTAGE 1/16W
J 2
(6525 -1650);
DISPLAY 0.510638 (6525 -1650);
FORCEPROP 1 LAST PACK_TYPE 0402LF
J 0
(6225 -1650);
DISPLAY 0.510638 (6225 -1650);
FORCEPROP 1 LAST $LOCATION R3185
J 0
(6100 -1775);
DISPLAY 0.638298 (6100 -1775);
FORCEPROP 1 LASTPIN (6250 -1775) $PN 1
J 0
(6262 -1763);
DISPLAY 0.787234 (6262 -1763);
FORCEPROP 1 LASTPIN (6450 -1775) $PN 2
J 0
(6412 -1763);
DISPLAY 0.787234 (6412 -1763);
FORCEPROP 1 LAST PATH I24
J 0
(6300 -1625);
DISPLAY 0.978723 (6300 -1625);
PAINT WHITE (6300 -1625);
DISPLAY INVISIBLE (6300 -1625);
FORCEPROP 2 LAST CDS_LIB pure_quanta
J 0
(6350 -1775);
PAINT MONO (6350 -1775);
DISPLAY INVISIBLE (6350 -1775);
FORCEPROP 2 LAST CDS_LOCATION R3185
J 0
(6300 -1575);
DISPLAY 1.021277 (6300 -1575);
DISPLAY INVISIBLE (6300 -1575);
FORCEPROP 2 LAST $SEC 1
J 0
(6300 -1575);
DISPLAY 0.680851 (6300 -1575);
PAINT MONO (6300 -1575);
DISPLAY INVISIBLE (6300 -1575);
FORCEPROP 2 LAST CDS_SEC 1
J 0
(6300 -1575);
DISPLAY 1.021277 (6300 -1575);
DISPLAY INVISIBLE (6300 -1575);
FORCEADD UNIVERSAL_POWER..1
(5200 -950);
FORCEPROP 3 LASTPIN (5200 -1000) SIG_NAME P3V3_AUX\g
J 0
(5210 -990);
DISPLAY 0.659574 (5210 -990);
PAINT MONO (5210 -990);
DISPLAY INVISIBLE (5210 -990);
FORCEPROP 1 LAST HDL_POWER P3V3_AUX
J 1
(5200 -900);
DISPLAY 0.872340 (5200 -900);
PAINT GREEN (5200 -900);
FORCEPROP 1 LAST PATH I25
J 0
(5250 -925);
DISPLAY 0.872340 (5250 -925);
PAINT AQUA (5250 -925);
DISPLAY INVISIBLE (5250 -925);
FORCEPROP 2 LAST CDS_LIB logical_power
J 0
(5200 -950);
PAINT MONO (5200 -950);
DISPLAY INVISIBLE (5200 -950);
FORCEADD UNIVERSAL_GND..1
(5200 -1500);
FORCEPROP 3 LASTPIN (5200 -1450) SIG_NAME GND\g
J 0
(5210 -1440);
DISPLAY 0.659574 (5210 -1440);
PAINT MONO (5210 -1440);
DISPLAY INVISIBLE (5210 -1440);
FORCEPROP 1 LAST HDL_POWER GND
J 1
(5225 -1575);
DISPLAY 0.872340 (5225 -1575);
PAINT GREEN (5225 -1575);
DISPLAY INVISIBLE (5225 -1575);
FORCEPROP 2 LAST CDS_LIB logical_power
J 0
(5200 -1500);
PAINT MONO (5200 -1500);
DISPLAY INVISIBLE (5200 -1500);
FORCEPROP 1 LAST PATH I26
J 0
(5275 -1500);
DISPLAY 0.872340 (5275 -1500);
PAINT AQUA (5275 -1500);
DISPLAY INVISIBLE (5275 -1500);
FORCEADD Q_CAP..1
(5200 -1275);
FORCEPROP 1 LAST PART_NUMBER CH4104K1B00
J 0
(5250 -1425);
DISPLAY 0.510638 (5250 -1425);
DISPLAY INVISIBLE (5250 -1425);
FORCEPROP 1 LAST PACK_TYPE 0402
J 0
(5250 -1475);
DISPLAY 0.510638 (5250 -1475);
FORCEPROP 1 LAST MATERIAL X7R
J 0
(5250 -1375);
DISPLAY 0.510638 (5250 -1375);
FORCEPROP 1 LAST TOLERANCE 10%
J 0
(5250 -1325);
DISPLAY 0.510638 (5250 -1325);
FORCEPROP 1 LAST VOLTAGE 25V
J 0
(5250 -1275);
DISPLAY 0.510638 (5250 -1275);
FORCEPROP 1 LAST VALUE 0.1UF
J 0
(5250 -1225);
DISPLAY 0.510638 (5250 -1225);
FORCEPROP 1 LAST $LOCATION C1822
J 0
(5250 -1175);
DISPLAY 0.978723 (5250 -1175);
FORCEPROP 1 LASTPIN (5200 -1175) $PN 1
J 0
(5210 -1195);
DISPLAY 0.787234 (5210 -1195);
FORCEPROP 1 LASTPIN (5200 -1375) $PN 2
J 0
(5210 -1395);
DISPLAY 0.787234 (5210 -1395);
FORCEPROP 2 LAST CDS_LIB pure_quanta
J 2
(5200 -1275);
PAINT MONO (5200 -1275);
DISPLAY INVISIBLE (5200 -1275);
FORCEPROP 1 LAST PATH I27
J 0
(5250 -1125);
DISPLAY 0.978723 (5250 -1125);
PAINT WHITE (5250 -1125);
DISPLAY INVISIBLE (5250 -1125);
FORCEPROP 2 LAST CDS_LOCATION C1822
J 0
(5250 -1075);
DISPLAY 1.021277 (5250 -1075);
DISPLAY INVISIBLE (5250 -1075);
FORCEPROP 2 LAST $SEC 1
J 0
(5250 -1075);
DISPLAY 0.680851 (5250 -1075);
PAINT MONO (5250 -1075);
DISPLAY INVISIBLE (5250 -1075);
FORCEPROP 2 LAST CDS_SEC 1
J 0
(5250 -1075);
DISPLAY 1.021277 (5250 -1075);
DISPLAY INVISIBLE (5250 -1075);
FORCEADD Q_RES..2
(6025 -1325);
FORCEPROP 1 LAST PART_NUMBER CS24702FB06
J 0
(6065 -1450);
DISPLAY 0.787234 (6065 -1450);
DISPLAY INVISIBLE (6065 -1450);
FORCEPROP 1 LAST MATERIAL CHIP
J 0
(6065 -1400);
DISPLAY 0.787234 (6065 -1400);
FORCEPROP 1 LAST WATTAGE 1/16W
J 0
(6065 -1350);
DISPLAY 0.787234 (6065 -1350);
FORCEPROP 1 LAST TOLERANCE 1%
J 0
(6070 -1300);
DISPLAY 0.787234 (6070 -1300);
FORCEPROP 1 LAST VALUE 4.7K
J 0
(6070 -1250);
DISPLAY 0.787234 (6070 -1250);
FORCEPROP 1 LAST PACK_TYPE 0402LF
J 0
(6065 -1500);
DISPLAY 0.787234 (6065 -1500);
FORCEPROP 1 LAST $LOCATION R3184
J 0
(6070 -1200);
DISPLAY 0.978723 (6070 -1200);
FORCEPROP 1 LASTPIN (6025 -1225) $PN 1
J 0
(6030 -1263);
DISPLAY 0.787234 (6030 -1263);
PAINT MONO (6030 -1263);
FORCEPROP 1 LASTPIN (6025 -1425) $PN 2
J 0
(6030 -1415);
DISPLAY 0.787234 (6030 -1415);
PAINT MONO (6030 -1415);
FORCEPROP 1 LAST PATH I28
J 0
(6075 -1150);
DISPLAY 0.978723 (6075 -1150);
PAINT WHITE (6075 -1150);
DISPLAY INVISIBLE (6075 -1150);
FORCEPROP 2 LAST CDS_LIB pure_quanta
J 0
(6025 -1325);
DISPLAY INVISIBLE (6025 -1325);
FORCEPROP 0 LAST CDS_LOCATION R3184
J 0
(6075 -1150);
DISPLAY 1.021277 (6075 -1150);
DISPLAY INVISIBLE (6075 -1150);
FORCEPROP 0 LAST $SEC 1
J 0
(6075 -1150);
DISPLAY 0.680851 (6075 -1150);
PAINT MONO (6075 -1150);
DISPLAY INVISIBLE (6075 -1150);
FORCEPROP 0 LAST CDS_SEC 1
J 0
(6075 -1150);
DISPLAY 1.021277 (6075 -1150);
DISPLAY INVISIBLE (6075 -1150);
FORCEADD UNIVERSAL_POWER..1
(6025 -1125);
FORCEPROP 3 LASTPIN (6025 -1175) SIG_NAME P3V3_AUX\g
J 0
(6035 -1165);
DISPLAY 0.659574 (6035 -1165);
PAINT MONO (6035 -1165);
DISPLAY INVISIBLE (6035 -1165);
FORCEPROP 1 LAST HDL_POWER P3V3_AUX
J 1
(6025 -1075);
DISPLAY 0.872340 (6025 -1075);
PAINT GREEN (6025 -1075);
FORCEPROP 1 LAST PATH I29
J 0
(6075 -1100);
DISPLAY 0.872340 (6075 -1100);
PAINT AQUA (6075 -1100);
DISPLAY INVISIBLE (6075 -1100);
FORCEPROP 2 LAST CDS_LIB logical_power
J 0
(6025 -1125);
DISPLAY INVISIBLE (6025 -1125);
FORCEADD UNIVERSAL_GND..1
(5350 -775);
FORCEPROP 3 LASTPIN (5350 -725) SIG_NAME GND\g
J 0
(5360 -715);
DISPLAY 0.659574 (5360 -715);
PAINT MONO (5360 -715);
DISPLAY INVISIBLE (5360 -715);
FORCEPROP 1 LAST HDL_POWER GND
J 1
(5375 -850);
DISPLAY 0.872340 (5375 -850);
PAINT GREEN (5375 -850);
DISPLAY INVISIBLE (5375 -850);
FORCEPROP 2 LAST CDS_LIB logical_power
J 0
(5350 -775);
PAINT MONO (5350 -775);
DISPLAY INVISIBLE (5350 -775);
FORCEPROP 1 LAST PATH I30
J 0
(5425 -775);
DISPLAY 0.872340 (5425 -775);
PAINT AQUA (5425 -775);
DISPLAY INVISIBLE (5425 -775);
FORCEADD 74LVC1G07GV..1
(5825 -450);
FORCEPROP 1 LAST PART_NUMBER AL1G0007001
J 0
(5700 -200);
DISPLAY 0.723404 (5700 -200);
PAINT GREEN (5700 -200);
DISPLAY INVISIBLE (5700 -200);
FORCEPROP 2 LAST PART_TYPE SMLF
J 0
(5700 25);
DISPLAY 0.638298 (5700 25);
FORCEPROP 1 LAST MATERIAL IC
J 0
(5706 -268);
DISPLAY 0.723404 (5706 -268);
PAINT GREEN (5706 -268);
FORCEPROP 2 LAST VALUE 74LVC1G07GV
J 0
(5700 -25);
DISPLAY 0.638298 (5700 -25);
FORCEPROP 1 LAST $LOCATION U218
J 0
(5700 -125);
DISPLAY 0.723404 (5700 -125);
PAINT GREEN (5700 -125);
FORCEPROP 0 LASTPIN (5550 -450) $PN 2
J 2
(5540 -440);
DISPLAY 0.680851 (5540 -440);
PAINT MONO (5540 -440);
FORCEPROP 0 LASTPIN (5550 -550) $PN 3
J 2
(5540 -540);
DISPLAY 0.680851 (5540 -540);
PAINT MONO (5540 -540);
FORCEPROP 0 LASTPIN (5550 -350) $PN 1
J 2
(5540 -340);
DISPLAY 0.680851 (5540 -340);
PAINT MONO (5540 -340);
FORCEPROP 0 LASTPIN (6100 -350) $PN 5
J 0
(6110 -340);
DISPLAY 0.680851 (6110 -340);
PAINT MONO (6110 -340);
FORCEPROP 0 LASTPIN (6100 -550) $PN 4
J 0
(6110 -540);
DISPLAY 0.680851 (6110 -540);
PAINT MONO (6110 -540);
FORCEPROP 2 LAST CDS_LIB pure_quanta
J 0
(5825 -450);
DISPLAY INVISIBLE (5825 -450);
FORCEPROP 1 LAST NEEDS_NO_SIZE TRUE
J 0
(5825 -450);
DISPLAY 0.723404 (5825 -450);
PAINT GREEN (5825 -450);
DISPLAY INVISIBLE (5825 -450);
FORCEPROP 1 LAST CDS_LMAN_SYM_OUTLINE -125,150,125,-150
J 0
(5825 -450);
DISPLAY 0.468085 (5825 -450);
PAINT GREEN (5825 -450);
DISPLAY INVISIBLE (5825 -450);
FORCEPROP 1 LAST PATH I31
J 0
(5825 -450);
DISPLAY 0.723404 (5825 -450);
PAINT GREEN (5825 -450);
DISPLAY INVISIBLE (5825 -450);
FORCEPROP 0 LAST CDS_LOCATION U218
J 0
(5700 75);
DISPLAY 1.021277 (5700 75);
DISPLAY INVISIBLE (5700 75);
FORCEPROP 0 LAST $SEC 1
J 0
(5700 75);
DISPLAY 0.680851 (5700 75);
PAINT MONO (5700 75);
DISPLAY INVISIBLE (5700 75);
FORCEPROP 0 LAST CDS_SEC 1
J 0
(5700 75);
DISPLAY 1.021277 (5700 75);
DISPLAY INVISIBLE (5700 75);
FORCEADD UNIVERSAL_GND..1
(6500 -300);
FORCEPROP 3 LASTPIN (6500 -250) SIG_NAME GND\g
J 0
(6510 -240);
DISPLAY 0.659574 (6510 -240);
PAINT MONO (6510 -240);
DISPLAY INVISIBLE (6510 -240);
FORCEPROP 2 LAST CDS_LIB logical_power
J 0
(6500 -300);
PAINT MONO (6500 -300);
DISPLAY INVISIBLE (6500 -300);
FORCEPROP 1 LAST HDL_POWER GND
J 1
(6525 -375);
DISPLAY 0.872340 (6525 -375);
PAINT GREEN (6525 -375);
DISPLAY INVISIBLE (6525 -375);
FORCEPROP 1 LAST PATH I32
J 0
(6575 -300);
DISPLAY 0.872340 (6575 -300);
PAINT AQUA (6575 -300);
DISPLAY INVISIBLE (6575 -300);
FORCEADD Q_CAP..1
(6500 -75);
FORCEPROP 1 LAST PART_NUMBER CH4104K1B00
J 0
(6550 -225);
DISPLAY 0.510638 (6550 -225);
DISPLAY INVISIBLE (6550 -225);
FORCEPROP 1 LAST TOLERANCE 10%
J 0
(6550 -125);
DISPLAY 0.510638 (6550 -125);
FORCEPROP 1 LAST MATERIAL X7R
J 0
(6550 -175);
DISPLAY 0.510638 (6550 -175);
FORCEPROP 1 LAST VALUE 0.1UF
J 0
(6550 -25);
DISPLAY 0.510638 (6550 -25);
FORCEPROP 1 LAST VOLTAGE 25V
J 0
(6550 -75);
DISPLAY 0.510638 (6550 -75);
FORCEPROP 1 LAST PACK_TYPE 0402
J 0
(6550 -275);
DISPLAY 0.510638 (6550 -275);
FORCEPROP 1 LAST $LOCATION C1823
J 0
(6550 25);
DISPLAY 0.978723 (6550 25);
FORCEPROP 1 LASTPIN (6500 25) $PN 1
J 0
(6510 5);
DISPLAY 0.787234 (6510 5);
FORCEPROP 1 LASTPIN (6500 -175) $PN 2
J 0
(6510 -195);
DISPLAY 0.787234 (6510 -195);
FORCEPROP 2 LAST CDS_LIB pure_quanta
J 2
(6500 -75);
PAINT MONO (6500 -75);
DISPLAY INVISIBLE (6500 -75);
FORCEPROP 1 LAST PATH I33
J 0
(6550 75);
DISPLAY 0.978723 (6550 75);
PAINT WHITE (6550 75);
DISPLAY INVISIBLE (6550 75);
FORCEPROP 2 LAST CDS_LOCATION C1823
J 0
(6550 125);
DISPLAY 1.021277 (6550 125);
DISPLAY INVISIBLE (6550 125);
FORCEPROP 2 LAST $SEC 1
J 0
(6550 125);
DISPLAY 0.680851 (6550 125);
PAINT MONO (6550 125);
DISPLAY INVISIBLE (6550 125);
FORCEPROP 2 LAST CDS_SEC 1
J 0
(6550 125);
DISPLAY 1.021277 (6550 125);
DISPLAY INVISIBLE (6550 125);
FORCEADD UNIVERSAL_GND..1
(5375 850);
FORCEPROP 3 LASTPIN (5375 900) SIG_NAME GND\g
J 0
(5385 910);
DISPLAY 0.659574 (5385 910);
PAINT MONO (5385 910);
DISPLAY INVISIBLE (5385 910);
FORCEPROP 2 LAST CDS_LIB logical_power
J 0
(5375 850);
PAINT MONO (5375 850);
DISPLAY INVISIBLE (5375 850);
FORCEPROP 1 LAST HDL_POWER GND
J 1
(5400 775);
DISPLAY 0.872340 (5400 775);
PAINT GREEN (5400 775);
DISPLAY INVISIBLE (5400 775);
FORCEPROP 1 LAST PATH I34
J 0
(5450 850);
DISPLAY 0.872340 (5450 850);
PAINT AQUA (5450 850);
DISPLAY INVISIBLE (5450 850);
FORCEADD 74LVC1G17GW..1
(5550 1100);
FORCEPROP 1 LAST PART_NUMBER AL1G0017K01
J 0
(5416 1334);
DISPLAY 0.723404 (5416 1334);
PAINT GREEN (5416 1334);
DISPLAY INVISIBLE (5416 1334);
FORCEPROP 1 LAST MATERIAL IC
J 0
(5416 1254);
DISPLAY 0.723404 (5416 1254);
PAINT GREEN (5416 1254);
FORCEPROP 2 LAST PART_TYPE SMLF
J 0
(5425 1475);
DISPLAY 0.638298 (5425 1475);
FORCEPROP 2 LAST VALUE 74LVC1G17GW
J 0
(5425 1425);
DISPLAY 0.638298 (5425 1425);
FORCEPROP 1 LAST $LOCATION U207
J 0
(5425 1375);
DISPLAY 0.723404 (5425 1375);
PAINT GREEN (5425 1375);
FORCEPROP 2 LASTPIN (5375 1100) $PN 2
J 2
(5365 1110);
DISPLAY 0.680851 (5365 1110);
PAINT MONO (5365 1110);
FORCEPROP 2 LASTPIN (5375 1000) $PN 3
J 2
(5365 1010);
DISPLAY 0.680851 (5365 1010);
PAINT MONO (5365 1010);
FORCEPROP 2 LASTPIN (5725 1000) $PN 1
J 0
(5735 1010);
DISPLAY 0.680851 (5735 1010);
PAINT MONO (5735 1010);
FORCEPROP 2 LASTPIN (5375 1200) $PN 5
J 2
(5365 1210);
DISPLAY 0.680851 (5365 1210);
PAINT MONO (5365 1210);
FORCEPROP 2 LASTPIN (5725 1100) $PN 4
J 0
(5735 1110);
DISPLAY 0.680851 (5735 1110);
PAINT MONO (5735 1110);
FORCEPROP 1 LAST PIN_NAMES_ROTATE True
J 0
(5550 1100);
DISPLAY 0.489362 (5550 1100);
PAINT GREEN (5550 1100);
DISPLAY INVISIBLE (5550 1100);
FORCEPROP 1 LAST CDS_LMAN_SYM_OUTLINE -125,150,125,-150
J 0
(5550 1100);
DISPLAY 0.468085 (5550 1100);
PAINT GREEN (5550 1100);
DISPLAY INVISIBLE (5550 1100);
FORCEPROP 2 LAST CDS_LIB pure_quanta
J 0
(5550 1100);
DISPLAY INVISIBLE (5550 1100);
FORCEPROP 2 LAST SEC_TYPE 
J 0
(5450 1475);
DISPLAY 1.021277 (5450 1475);
DISPLAY INVISIBLE (5450 1475);
FORCEPROP 1 LAST PATH I35
J 0
(5675 950);
DISPLAY 0.723404 (5675 950);
PAINT GREEN (5675 950);
DISPLAY INVISIBLE (5675 950);
FORCEPROP 2 LAST CDS_LOCATION U207
J 0
(5450 1475);
DISPLAY 1.021277 (5450 1475);
DISPLAY INVISIBLE (5450 1475);
FORCEPROP 2 LAST SEC 1
J 0
(5450 1475);
DISPLAY 0.680851 (5450 1475);
PAINT MONO (5450 1475);
DISPLAY INVISIBLE (5450 1475);
FORCEADD UNIVERSAL_POWER..1
(5250 1700);
FORCEPROP 3 LASTPIN (5250 1650) SIG_NAME P3V3_AUX\g
J 0
(5260 1660);
DISPLAY 0.659574 (5260 1660);
PAINT MONO (5260 1660);
DISPLAY INVISIBLE (5260 1660);
FORCEPROP 1 LAST HDL_POWER P3V3_AUX
J 1
(5250 1750);
DISPLAY 0.872340 (5250 1750);
PAINT GREEN (5250 1750);
FORCEPROP 2 LAST CDS_LIB logical_power
J 0
(5250 1700);
PAINT MONO (5250 1700);
DISPLAY INVISIBLE (5250 1700);
FORCEPROP 1 LAST PATH I36
J 0
(5300 1725);
DISPLAY 0.872340 (5300 1725);
PAINT AQUA (5300 1725);
DISPLAY INVISIBLE (5300 1725);
FORCEADD UNIVERSAL_POWER..1
(6300 200);
FORCEPROP 3 LASTPIN (6300 150) SIG_NAME P3V3_AUX\g
J 0
(6310 160);
DISPLAY 0.659574 (6310 160);
PAINT MONO (6310 160);
DISPLAY INVISIBLE (6310 160);
FORCEPROP 1 LAST HDL_POWER P3V3_AUX
J 1
(6300 250);
DISPLAY 0.872340 (6300 250);
PAINT GREEN (6300 250);
FORCEPROP 2 LAST CDS_LIB logical_power
J 0
(6300 200);
PAINT MONO (6300 200);
DISPLAY INVISIBLE (6300 200);
FORCEPROP 1 LAST PATH I37
J 0
(6350 225);
DISPLAY 0.872340 (6350 225);
PAINT AQUA (6350 225);
DISPLAY INVISIBLE (6350 225);
FORCEADD Q_RES..1
(7000 425);
FORCEPROP 1 LAST PART_NUMBER CS03322FB03
J 0
(6900 500);
DISPLAY 0.510638 (6900 500);
DISPLAY INVISIBLE (6900 500);
FORCEPROP 1 LAST MATERIAL CHIP
J 0
(6900 550);
DISPLAY 0.510638 (6900 550);
FORCEPROP 1 LAST WATTAGE 1/16W
J 2
(7175 550);
DISPLAY 0.510638 (7175 550);
FORCEPROP 1 LAST TOLERANCE 1%
J 0
(7225 425);
DISPLAY 0.510638 (7225 425);
FORCEPROP 1 LAST VALUE 33.2
J 2
(7200 425);
DISPLAY 0.510638 (7200 425);
FORCEPROP 1 LAST PACK_TYPE 0402LF
J 0
(7300 425);
DISPLAY 0.510638 (7300 425);
FORCEPROP 1 LAST $LOCATION R3189
J 0
(6725 425);
DISPLAY 0.510638 (6725 425);
FORCEPROP 1 LASTPIN (6900 425) $PN 1
J 0
(6912 437);
DISPLAY 0.787234 (6912 437);
FORCEPROP 1 LASTPIN (7100 425) $PN 2
J 0
(7062 437);
DISPLAY 0.787234 (7062 437);
FORCEPROP 2 LAST CDS_LIB pure_quanta
J 0
(7000 425);
PAINT MONO (7000 425);
DISPLAY INVISIBLE (7000 425);
FORCEPROP 1 LAST PATH I38
J 0
(6950 575);
DISPLAY 0.978723 (6950 575);
PAINT WHITE (6950 575);
DISPLAY INVISIBLE (6950 575);
FORCEPROP 2 LAST CDS_LOCATION R3189
J 0
(6950 625);
DISPLAY 1.021277 (6950 625);
DISPLAY INVISIBLE (6950 625);
FORCEPROP 2 LAST $SEC 1
J 0
(6950 625);
DISPLAY 0.680851 (6950 625);
PAINT MONO (6950 625);
DISPLAY INVISIBLE (6950 625);
FORCEPROP 2 LAST CDS_SEC 1
J 0
(6950 625);
DISPLAY 1.021277 (6950 625);
DISPLAY INVISIBLE (6950 625);
FORCEADD Q_RES..1
(7000 650);
FORCEPROP 1 LAST PART_NUMBER CS03322FB03
J 0
(6900 725);
DISPLAY 0.510638 (6900 725);
DISPLAY INVISIBLE (6900 725);
FORCEPROP 1 LAST TOLERANCE 1%
J 0
(7225 650);
DISPLAY 0.510638 (7225 650);
FORCEPROP 1 LAST WATTAGE 1/16W
J 2
(7175 775);
DISPLAY 0.510638 (7175 775);
FORCEPROP 1 LAST VALUE 33.2
J 2
(7200 650);
DISPLAY 0.510638 (7200 650);
FORCEPROP 1 LAST PACK_TYPE 0402LF
J 0
(7300 650);
DISPLAY 0.510638 (7300 650);
FORCEPROP 1 LAST MATERIAL CHIP
J 0
(6900 775);
DISPLAY 0.510638 (6900 775);
FORCEPROP 1 LAST $LOCATION R3188
J 0
(6725 650);
DISPLAY 0.510638 (6725 650);
FORCEPROP 1 LASTPIN (6900 650) $PN 1
J 0
(6912 662);
DISPLAY 0.787234 (6912 662);
FORCEPROP 1 LASTPIN (7100 650) $PN 2
J 0
(7062 662);
DISPLAY 0.787234 (7062 662);
FORCEPROP 2 LAST CDS_LIB pure_quanta
J 0
(7000 650);
PAINT MONO (7000 650);
DISPLAY INVISIBLE (7000 650);
FORCEPROP 1 LAST PATH I39
J 0
(6950 800);
DISPLAY 0.978723 (6950 800);
PAINT WHITE (6950 800);
DISPLAY INVISIBLE (6950 800);
FORCEPROP 2 LAST CDS_LOCATION R3188
J 0
(6950 850);
DISPLAY 1.021277 (6950 850);
DISPLAY INVISIBLE (6950 850);
FORCEPROP 2 LAST $SEC 1
J 0
(6950 850);
DISPLAY 0.680851 (6950 850);
PAINT MONO (6950 850);
DISPLAY INVISIBLE (6950 850);
FORCEPROP 2 LAST CDS_SEC 1
J 0
(6950 850);
DISPLAY 1.021277 (6950 850);
DISPLAY INVISIBLE (6950 850);
FORCEADD Q_RES..1
(7000 875);
FORCEPROP 1 LAST PART_NUMBER CS03322FB03
J 0
(6900 950);
DISPLAY 0.510638 (6900 950);
DISPLAY INVISIBLE (6900 950);
FORCEPROP 1 LAST MATERIAL CHIP
J 0
(6900 1000);
DISPLAY 0.510638 (6900 1000);
FORCEPROP 1 LAST PACK_TYPE 0402LF
J 0
(7300 875);
DISPLAY 0.510638 (7300 875);
FORCEPROP 1 LAST TOLERANCE 1%
J 0
(7225 875);
DISPLAY 0.510638 (7225 875);
FORCEPROP 1 LAST VALUE 33.2
J 2
(7200 875);
DISPLAY 0.510638 (7200 875);
FORCEPROP 1 LAST WATTAGE 1/16W
J 2
(7175 1000);
DISPLAY 0.510638 (7175 1000);
FORCEPROP 1 LAST $LOCATION R3187
J 0
(6725 875);
DISPLAY 0.510638 (6725 875);
FORCEPROP 1 LASTPIN (6900 875) $PN 1
J 0
(6912 887);
DISPLAY 0.787234 (6912 887);
FORCEPROP 1 LASTPIN (7100 875) $PN 2
J 0
(7062 887);
DISPLAY 0.787234 (7062 887);
FORCEPROP 2 LAST CDS_LIB pure_quanta
J 0
(7000 875);
PAINT MONO (7000 875);
DISPLAY INVISIBLE (7000 875);
FORCEPROP 1 LAST PATH I40
J 0
(6950 1025);
DISPLAY 0.978723 (6950 1025);
PAINT WHITE (6950 1025);
DISPLAY INVISIBLE (6950 1025);
FORCEPROP 2 LAST CDS_LOCATION R3187
J 0
(6950 1075);
DISPLAY 1.021277 (6950 1075);
DISPLAY INVISIBLE (6950 1075);
FORCEPROP 2 LAST $SEC 1
J 0
(6950 1075);
DISPLAY 0.680851 (6950 1075);
PAINT MONO (6950 1075);
DISPLAY INVISIBLE (6950 1075);
FORCEPROP 2 LAST CDS_SEC 1
J 0
(6950 1075);
DISPLAY 1.021277 (6950 1075);
DISPLAY INVISIBLE (6950 1075);
FORCEADD Q_RES..1
(7000 1100);
FORCEPROP 1 LAST PART_NUMBER CS03322FB03
J 0
(6900 1175);
DISPLAY 0.510638 (6900 1175);
DISPLAY INVISIBLE (6900 1175);
FORCEPROP 1 LAST MATERIAL CHIP
J 0
(6900 1225);
DISPLAY 0.510638 (6900 1225);
FORCEPROP 1 LAST TOLERANCE 1%
J 0
(7225 1100);
DISPLAY 0.510638 (7225 1100);
FORCEPROP 1 LAST PACK_TYPE 0402LF
J 0
(7300 1100);
DISPLAY 0.510638 (7300 1100);
FORCEPROP 1 LAST WATTAGE 1/16W
J 2
(7175 1225);
DISPLAY 0.510638 (7175 1225);
FORCEPROP 1 LAST VALUE 33.2
J 2
(7200 1100);
DISPLAY 0.510638 (7200 1100);
FORCEPROP 1 LAST $LOCATION R3186
J 0
(6725 1100);
DISPLAY 0.510638 (6725 1100);
FORCEPROP 1 LASTPIN (6900 1100) $PN 1
J 0
(6912 1112);
DISPLAY 0.787234 (6912 1112);
FORCEPROP 1 LASTPIN (7100 1100) $PN 2
J 0
(7062 1112);
DISPLAY 0.787234 (7062 1112);
FORCEPROP 2 LAST CDS_LIB pure_quanta
J 0
(7000 1100);
PAINT MONO (7000 1100);
DISPLAY INVISIBLE (7000 1100);
FORCEPROP 1 LAST PATH I41
J 0
(6950 1250);
DISPLAY 0.978723 (6950 1250);
PAINT WHITE (6950 1250);
DISPLAY INVISIBLE (6950 1250);
FORCEPROP 2 LAST CDS_LOCATION R3186
J 0
(6950 1300);
DISPLAY 1.021277 (6950 1300);
DISPLAY INVISIBLE (6950 1300);
FORCEPROP 2 LAST $SEC 1
J 0
(6950 1300);
DISPLAY 0.680851 (6950 1300);
PAINT MONO (6950 1300);
DISPLAY INVISIBLE (6950 1300);
FORCEPROP 2 LAST CDS_SEC 1
J 0
(6950 1300);
DISPLAY 1.021277 (6950 1300);
DISPLAY INVISIBLE (6950 1300);
FORCEADD Q_RES..2
(7200 -175);
FORCEPROP 1 LAST PART_NUMBER CS24702FB06
J 0
(7240 -300);
DISPLAY 0.787234 (7240 -300);
DISPLAY INVISIBLE (7240 -300);
FORCEPROP 1 LAST VALUE 4.7K
J 0
(7245 -100);
DISPLAY 0.787234 (7245 -100);
FORCEPROP 1 LAST TOLERANCE 1%
J 0
(7245 -150);
DISPLAY 0.787234 (7245 -150);
FORCEPROP 1 LAST WATTAGE 1/16W
J 0
(7240 -200);
DISPLAY 0.787234 (7240 -200);
FORCEPROP 1 LAST PACK_TYPE 0402LF
J 0
(7240 -350);
DISPLAY 0.787234 (7240 -350);
FORCEPROP 1 LAST MATERIAL CHIP
J 0
(7240 -250);
DISPLAY 0.787234 (7240 -250);
FORCEPROP 1 LAST $LOCATION R3190
J 0
(7245 -50);
DISPLAY 0.787234 (7245 -50);
FORCEPROP 1 LASTPIN (7200 -75) $PN 1
J 0
(7205 -113);
DISPLAY 0.787234 (7205 -113);
FORCEPROP 1 LASTPIN (7200 -275) $PN 2
J 0
(7205 -265);
DISPLAY 0.787234 (7205 -265);
FORCEPROP 1 LAST PATH I42
J 0
(7250 0);
DISPLAY 0.978723 (7250 0);
PAINT WHITE (7250 0);
DISPLAY INVISIBLE (7250 0);
FORCEPROP 2 LAST CDS_LIB pure_quanta
J 0
(7200 -175);
PAINT MONO (7200 -175);
DISPLAY INVISIBLE (7200 -175);
FORCEPROP 2 LAST CDS_LOCATION R3190
J 0
(7250 50);
DISPLAY 1.021277 (7250 50);
DISPLAY INVISIBLE (7250 50);
FORCEPROP 2 LAST $SEC 1
J 0
(7250 50);
DISPLAY 0.680851 (7250 50);
PAINT MONO (7250 50);
DISPLAY INVISIBLE (7250 50);
FORCEPROP 2 LAST CDS_SEC 1
J 0
(7250 50);
DISPLAY 1.021277 (7250 50);
DISPLAY INVISIBLE (7250 50);
FORCEADD UNIVERSAL_POWER..1
(7200 25);
FORCEPROP 3 LASTPIN (7200 -25) SIG_NAME P3V3_AUX\g
J 0
(7210 -15);
DISPLAY 0.659574 (7210 -15);
PAINT MONO (7210 -15);
DISPLAY INVISIBLE (7210 -15);
FORCEPROP 1 LAST HDL_POWER P3V3_AUX
J 1
(7200 75);
DISPLAY 0.872340 (7200 75);
PAINT GREEN (7200 75);
FORCEPROP 2 LAST CDS_LIB logical_power
J 0
(7200 25);
PAINT MONO (7200 25);
DISPLAY INVISIBLE (7200 25);
FORCEPROP 1 LAST PATH I43
J 0
(7250 50);
DISPLAY 0.872340 (7250 50);
PAINT AQUA (7250 50);
DISPLAY INVISIBLE (7250 50);
FORCEADD Q_RES..1
(7750 -550);
FORCEPROP 1 LAST PART_NUMBER CS03322FB03
J 0
(7650 -475);
DISPLAY 0.510638 (7650 -475);
DISPLAY INVISIBLE (7650 -475);
FORCEPROP 1 LAST PACK_TYPE 0402LF
J 0
(8050 -550);
DISPLAY 0.510638 (8050 -550);
FORCEPROP 1 LAST MATERIAL CHIP
J 0
(7650 -425);
DISPLAY 0.510638 (7650 -425);
FORCEPROP 1 LAST VALUE 33.2
J 2
(7950 -550);
DISPLAY 0.510638 (7950 -550);
FORCEPROP 1 LAST WATTAGE 1/16W
J 2
(7925 -425);
DISPLAY 0.510638 (7925 -425);
FORCEPROP 1 LAST TOLERANCE 1%
J 0
(7975 -550);
DISPLAY 0.510638 (7975 -550);
FORCEPROP 1 LAST $LOCATION R3191
J 0
(7475 -550);
DISPLAY 0.638298 (7475 -550);
FORCEPROP 1 LASTPIN (7650 -550) $PN 1
J 0
(7662 -538);
DISPLAY 0.787234 (7662 -538);
FORCEPROP 1 LASTPIN (7850 -550) $PN 2
J 0
(7812 -538);
DISPLAY 0.787234 (7812 -538);
FORCEPROP 2 LAST CDS_LIB pure_quanta
J 0
(7750 -550);
PAINT MONO (7750 -550);
DISPLAY INVISIBLE (7750 -550);
FORCEPROP 1 LAST PATH I44
J 0
(7700 -400);
DISPLAY 0.978723 (7700 -400);
PAINT WHITE (7700 -400);
DISPLAY INVISIBLE (7700 -400);
FORCEPROP 2 LAST CDS_LOCATION R3191
J 0
(7700 -350);
DISPLAY 1.021277 (7700 -350);
DISPLAY INVISIBLE (7700 -350);
FORCEPROP 2 LAST $SEC 1
J 0
(7700 -350);
DISPLAY 0.680851 (7700 -350);
PAINT MONO (7700 -350);
DISPLAY INVISIBLE (7700 -350);
FORCEPROP 2 LAST CDS_SEC 1
J 0
(7700 -350);
DISPLAY 1.021277 (7700 -350);
DISPLAY INVISIBLE (7700 -350);
FORCEADD UNIVERSAL_POWER..1
(8550 -1225);
FORCEPROP 3 LASTPIN (8550 -1275) SIG_NAME P3V3_AUX\g
J 0
(8560 -1265);
DISPLAY 0.659574 (8560 -1265);
PAINT MONO (8560 -1265);
DISPLAY INVISIBLE (8560 -1265);
FORCEPROP 1 LAST HDL_POWER P3V3_AUX
J 1
(8550 -1175);
DISPLAY 0.872340 (8550 -1175);
PAINT GREEN (8550 -1175);
FORCEPROP 1 LAST PATH I45
J 0
(8600 -1200);
DISPLAY 0.872340 (8600 -1200);
PAINT AQUA (8600 -1200);
DISPLAY INVISIBLE (8600 -1200);
FORCEPROP 2 LAST CDS_LIB logical_power
J 0
(8550 -1225);
DISPLAY INVISIBLE (8550 -1225);
FORCEADD UNIVERSAL_GND..1
(8750 -1725);
FORCEPROP 3 LASTPIN (8750 -1675) SIG_NAME GND\g
J 0
(8760 -1665);
DISPLAY 0.659574 (8760 -1665);
PAINT MONO (8760 -1665);
DISPLAY INVISIBLE (8760 -1665);
FORCEPROP 1 LAST PATH I46
J 0
(8825 -1725);
DISPLAY 0.872340 (8825 -1725);
PAINT AQUA (8825 -1725);
DISPLAY INVISIBLE (8825 -1725);
FORCEPROP 1 LAST HDL_POWER GND
J 1
(8775 -1800);
DISPLAY 0.872340 (8775 -1800);
PAINT GREEN (8775 -1800);
DISPLAY INVISIBLE (8775 -1800);
FORCEPROP 2 LAST CDS_LIB logical_power
J 0
(8750 -1725);
DISPLAY INVISIBLE (8750 -1725);
FORCEADD Q_CAP..1
(8750 -1500);
FORCEPROP 1 LAST PART_NUMBER CH4104K1B00
J 0
(8800 -1650);
DISPLAY 0.510638 (8800 -1650);
DISPLAY INVISIBLE (8800 -1650);
FORCEPROP 1 LAST VOLTAGE 25V
J 0
(8800 -1500);
DISPLAY 0.510638 (8800 -1500);
FORCEPROP 1 LAST VALUE 0.1UF
J 0
(8800 -1450);
DISPLAY 0.510638 (8800 -1450);
FORCEPROP 1 LAST MATERIAL X7R
J 0
(8800 -1600);
DISPLAY 0.510638 (8800 -1600);
FORCEPROP 1 LAST PACK_TYPE 0402
J 0
(8800 -1700);
DISPLAY 0.510638 (8800 -1700);
FORCEPROP 1 LAST TOLERANCE 10%
J 0
(8800 -1550);
DISPLAY 0.510638 (8800 -1550);
FORCEPROP 1 LAST $LOCATION C1824
J 0
(8800 -1400);
DISPLAY 0.978723 (8800 -1400);
FORCEPROP 1 LASTPIN (8750 -1400) $PN 1
J 0
(8760 -1420);
DISPLAY 0.787234 (8760 -1420);
PAINT MONO (8760 -1420);
FORCEPROP 1 LASTPIN (8750 -1600) $PN 2
J 0
(8760 -1620);
DISPLAY 0.787234 (8760 -1620);
PAINT MONO (8760 -1620);
FORCEPROP 1 LAST PATH I47
J 0
(8800 -1350);
DISPLAY 0.978723 (8800 -1350);
PAINT WHITE (8800 -1350);
DISPLAY INVISIBLE (8800 -1350);
FORCEPROP 2 LAST CDS_LIB pure_quanta
J 0
(8750 -1500);
DISPLAY INVISIBLE (8750 -1500);
FORCEPROP 0 LAST CDS_LOCATION C1824
J 0
(8800 -1350);
DISPLAY 1.021277 (8800 -1350);
DISPLAY INVISIBLE (8800 -1350);
FORCEPROP 0 LAST $SEC 1
J 0
(8800 -1350);
DISPLAY 0.680851 (8800 -1350);
PAINT MONO (8800 -1350);
DISPLAY INVISIBLE (8800 -1350);
FORCEPROP 0 LAST CDS_SEC 1
J 0
(8800 -1350);
DISPLAY 1.021277 (8800 -1350);
DISPLAY INVISIBLE (8800 -1350);
FORCEADD OFFPAGE..2
(9000 -550);
FORCEPROP 2 LAST $XR0 159 
J 0
(9189 -550);
DISPLAY 0.638298 (9189 -550);
PAINT MONO (9189 -550);
FORCEPROP 2 LAST CDS_LIB standard
J 0
(9000 -550);
PAINT MONO (9000 -550);
DISPLAY INVISIBLE (9000 -550);
FORCEPROP 1 LAST COMMENT_BODY TRUE
J 0
(8955 -645);
DISPLAY 0.872340 (8955 -645);
PAINT GREEN (8955 -645);
DISPLAY INVISIBLE (8955 -645);
FORCEPROP 1 LAST OFFPAGE TRUE
J 0
(9325 -675);
DISPLAY 0.872340 (9325 -675);
PAINT GREEN (9325 -675);
DISPLAY INVISIBLE (9325 -675);
FORCEPROP 2 LAST PATH I48
J 0
(9200 -500);
DISPLAY 1.021277 (9200 -500);
DISPLAY INVISIBLE (9200 -500);
FORCEADD OFFPAGE..2
(8625 425);
FORCEPROP 2 LAST $XR0 159 
J 0
(8814 425);
DISPLAY 0.638298 (8814 425);
PAINT MONO (8814 425);
FORCEPROP 1 LAST OFFPAGE TRUE
J 0
(8950 300);
DISPLAY 0.872340 (8950 300);
PAINT GREEN (8950 300);
DISPLAY INVISIBLE (8950 300);
FORCEPROP 1 LAST COMMENT_BODY TRUE
J 0
(8580 330);
DISPLAY 0.872340 (8580 330);
PAINT GREEN (8580 330);
DISPLAY INVISIBLE (8580 330);
FORCEPROP 2 LAST CDS_LIB standard
J 0
(8625 425);
PAINT MONO (8625 425);
DISPLAY INVISIBLE (8625 425);
FORCEPROP 2 LAST PATH I49
J 0
(8825 475);
DISPLAY 1.021277 (8825 475);
DISPLAY INVISIBLE (8825 475);
FORCEADD OFFPAGE..1
(2875 -1725);
FORCEPROP 2 LAST $XR0 159 
J 0
(2593 -1725);
DISPLAY 0.638298 (2593 -1725);
PAINT MONO (2593 -1725);
FORCEPROP 2 LAST PATH I5
J 0
(2625 -1675);
DISPLAY 1.021277 (2625 -1675);
DISPLAY INVISIBLE (2625 -1675);
FORCEPROP 1 LAST COMMENT_BODY TRUE
J 0
(3000 -1825);
DISPLAY 0.872340 (3000 -1825);
PAINT GREEN (3000 -1825);
DISPLAY INVISIBLE (3000 -1825);
FORCEPROP 1 LAST OFFPAGE TRUE
J 0
(3200 -1850);
DISPLAY 0.872340 (3200 -1850);
PAINT GREEN (3200 -1850);
DISPLAY INVISIBLE (3200 -1850);
FORCEPROP 2 LAST CDS_LIB standard
J 0
(2875 -1725);
PAINT MONO (2875 -1725);
DISPLAY INVISIBLE (2875 -1725);
FORCEADD OFFPAGE..2
(8625 650);
FORCEPROP 2 LAST $XR0 159 
J 0
(8814 650);
DISPLAY 0.638298 (8814 650);
PAINT MONO (8814 650);
FORCEPROP 1 LAST OFFPAGE TRUE
J 0
(8950 525);
DISPLAY 0.872340 (8950 525);
PAINT GREEN (8950 525);
DISPLAY INVISIBLE (8950 525);
FORCEPROP 1 LAST COMMENT_BODY TRUE
J 0
(8580 555);
DISPLAY 0.872340 (8580 555);
PAINT GREEN (8580 555);
DISPLAY INVISIBLE (8580 555);
FORCEPROP 2 LAST CDS_LIB standard
J 0
(8625 650);
PAINT MONO (8625 650);
DISPLAY INVISIBLE (8625 650);
FORCEPROP 2 LAST PATH I50
J 0
(8825 700);
DISPLAY 1.021277 (8825 700);
DISPLAY INVISIBLE (8825 700);
FORCEADD OFFPAGE..2
(8625 875);
FORCEPROP 2 LAST $XR0 159 
J 0
(8814 875);
DISPLAY 0.638298 (8814 875);
PAINT MONO (8814 875);
FORCEPROP 1 LAST OFFPAGE TRUE
J 0
(8950 750);
DISPLAY 0.872340 (8950 750);
PAINT GREEN (8950 750);
DISPLAY INVISIBLE (8950 750);
FORCEPROP 1 LAST COMMENT_BODY TRUE
J 0
(8580 780);
DISPLAY 0.872340 (8580 780);
PAINT GREEN (8580 780);
DISPLAY INVISIBLE (8580 780);
FORCEPROP 2 LAST CDS_LIB standard
J 0
(8625 875);
PAINT MONO (8625 875);
DISPLAY INVISIBLE (8625 875);
FORCEPROP 2 LAST PATH I51
J 0
(8825 925);
DISPLAY 1.021277 (8825 925);
DISPLAY INVISIBLE (8825 925);
FORCEADD OFFPAGE..2
(8625 1100);
FORCEPROP 2 LAST $XR0 159 
J 0
(8814 1100);
DISPLAY 0.638298 (8814 1100);
PAINT MONO (8814 1100);
FORCEPROP 2 LAST CDS_LIB standard
J 0
(8625 1100);
PAINT MONO (8625 1100);
DISPLAY INVISIBLE (8625 1100);
FORCEPROP 1 LAST COMMENT_BODY TRUE
J 0
(8580 1005);
DISPLAY 0.872340 (8580 1005);
PAINT GREEN (8580 1005);
DISPLAY INVISIBLE (8580 1005);
FORCEPROP 1 LAST OFFPAGE TRUE
J 0
(8950 975);
DISPLAY 0.872340 (8950 975);
PAINT GREEN (8950 975);
DISPLAY INVISIBLE (8950 975);
FORCEPROP 2 LAST PATH I52
J 0
(8825 1150);
DISPLAY 1.021277 (8825 1150);
DISPLAY INVISIBLE (8825 1150);
FORCEADD Q_RES..1
(9600 -1875);
FORCEPROP 1 LAST PART_NUMBER CS03322FB03
J 0
(9500 -1800);
DISPLAY 0.510638 (9500 -1800);
DISPLAY INVISIBLE (9500 -1800);
FORCEPROP 1 LAST PACK_TYPE 0402LF
J 0
(9475 -1750);
DISPLAY 0.510638 (9475 -1750);
FORCEPROP 1 LAST VALUE 33.2
J 2
(9800 -1875);
DISPLAY 0.510638 (9800 -1875);
FORCEPROP 1 LAST TOLERANCE 1%
J 0
(9825 -1875);
DISPLAY 0.510638 (9825 -1875);
FORCEPROP 1 LAST MATERIAL CHIP
J 0
(9900 -1875);
DISPLAY 0.510638 (9900 -1875);
FORCEPROP 1 LAST WATTAGE 1/16W
J 2
(9775 -1750);
DISPLAY 0.510638 (9775 -1750);
FORCEPROP 1 LAST $LOCATION R3193
J 0
(9350 -1875);
DISPLAY 0.638298 (9350 -1875);
FORCEPROP 1 LASTPIN (9500 -1875) $PN 1
J 0
(9512 -1863);
DISPLAY 0.787234 (9512 -1863);
PAINT MONO (9512 -1863);
FORCEPROP 1 LASTPIN (9700 -1875) $PN 2
J 0
(9662 -1863);
DISPLAY 0.787234 (9662 -1863);
PAINT MONO (9662 -1863);
FORCEPROP 1 LAST PATH I55
J 0
(9550 -1725);
DISPLAY 0.978723 (9550 -1725);
PAINT WHITE (9550 -1725);
DISPLAY INVISIBLE (9550 -1725);
FORCEPROP 2 LAST CDS_LIB pure_quanta
J 0
(9600 -1875);
DISPLAY INVISIBLE (9600 -1875);
FORCEPROP 0 LAST CDS_LOCATION R3193
J 0
(9775 -1725);
DISPLAY 1.021277 (9775 -1725);
DISPLAY INVISIBLE (9775 -1725);
FORCEPROP 0 LAST $SEC 1
J 0
(9775 -1725);
DISPLAY 0.680851 (9775 -1725);
PAINT MONO (9775 -1725);
DISPLAY INVISIBLE (9775 -1725);
FORCEPROP 0 LAST CDS_SEC 1
J 0
(9775 -1725);
DISPLAY 1.021277 (9775 -1725);
DISPLAY INVISIBLE (9775 -1725);
FORCEADD OFFPAGE..2
(10800 -1875);
FORCEPROP 2 LAST $XR2 182 
J 0
(11229 -1875);
DISPLAY 0.638298 (11229 -1875);
PAINT MONO (11229 -1875);
FORCEPROP 2 LAST $XR1 190 
J 0
(11109 -1875);
DISPLAY 0.638298 (11109 -1875);
PAINT MONO (11109 -1875);
FORCEPROP 2 LAST $XR0 155 
J 0
(10989 -1875);
DISPLAY 0.638298 (10989 -1875);
PAINT MONO (10989 -1875);
FORCEPROP 2 LAST CDS_LIB standard
J 0
(10800 -1875);
PAINT MONO (10800 -1875);
DISPLAY INVISIBLE (10800 -1875);
FORCEPROP 2 LAST PATH I58
J 0
(11350 -1825);
DISPLAY 1.021277 (11350 -1825);
DISPLAY INVISIBLE (11350 -1825);
FORCEPROP 1 LAST OFFPAGE TRUE
J 0
(11125 -2000);
DISPLAY 0.872340 (11125 -2000);
PAINT GREEN (11125 -2000);
DISPLAY INVISIBLE (11125 -2000);
FORCEPROP 1 LAST COMMENT_BODY TRUE
J 0
(10755 -1970);
DISPLAY 0.872340 (10755 -1970);
PAINT GREEN (10755 -1970);
DISPLAY INVISIBLE (10755 -1970);
FORCEADD Q_RES..2
(9300 -1425);
FORCEPROP 1 LAST PART_NUMBER CS24702FB06
J 0
(9340 -1550);
DISPLAY 0.638298 (9340 -1550);
DISPLAY INVISIBLE (9340 -1550);
FORCEPROP 1 LAST MATERIAL EMPTY
J 0
(9340 -1500);
DISPLAY 0.638298 (9340 -1500);
PAINT RED (9340 -1500);
FORCEPROP 1 LAST PACK_TYPE 0402LF
J 0
(9340 -1600);
DISPLAY 0.638298 (9340 -1600);
FORCEPROP 1 LAST TOLERANCE 1%
J 0
(9345 -1400);
DISPLAY 0.638298 (9345 -1400);
FORCEPROP 1 LAST VALUE 4.7K
J 0
(9345 -1350);
DISPLAY 0.638298 (9345 -1350);
FORCEPROP 1 LAST WATTAGE 1/16W
J 0
(9340 -1450);
DISPLAY 0.638298 (9340 -1450);
FORCEPROP 1 LAST $LOCATION R3192
J 0
(9345 -1300);
DISPLAY 0.978723 (9345 -1300);
FORCEPROP 1 LASTPIN (9300 -1325) $PN 1
J 0
(9305 -1363);
DISPLAY 0.787234 (9305 -1363);
PAINT MONO (9305 -1363);
FORCEPROP 1 LASTPIN (9300 -1525) $PN 2
J 0
(9305 -1515);
DISPLAY 0.787234 (9305 -1515);
PAINT MONO (9305 -1515);
FORCEPROP 1 LAST PATH I59
J 0
(9350 -1250);
DISPLAY 0.978723 (9350 -1250);
PAINT WHITE (9350 -1250);
DISPLAY INVISIBLE (9350 -1250);
FORCEPROP 2 LAST CDS_LIB pure_quanta
J 0
(9300 -1425);
DISPLAY INVISIBLE (9300 -1425);
FORCEPROP 0 LAST CDS_LOCATION R3192
J 0
(9350 -1250);
DISPLAY 1.021277 (9350 -1250);
DISPLAY INVISIBLE (9350 -1250);
FORCEPROP 0 LAST $SEC 1
J 0
(9350 -1250);
DISPLAY 0.680851 (9350 -1250);
PAINT MONO (9350 -1250);
DISPLAY INVISIBLE (9350 -1250);
FORCEPROP 0 LAST CDS_SEC 1
J 0
(9350 -1250);
DISPLAY 1.021277 (9350 -1250);
DISPLAY INVISIBLE (9350 -1250);
FORCEADD Q_RES..2
R 2
(3400 -1425);
FORCEPROP 1 LAST PART_NUMBER CS31002FB08
J 2
(3360 -1550);
DISPLAY 0.638298 (3360 -1550);
DISPLAY INVISIBLE (3360 -1550);
FORCEPROP 1 LAST MATERIAL CHIP
J 2
(3360 -1500);
DISPLAY 0.638298 (3360 -1500);
FORCEPROP 1 LAST PACK_TYPE 0402LF
J 2
(3360 -1600);
DISPLAY 0.638298 (3360 -1600);
FORCEPROP 1 LAST WATTAGE 1/16W
J 2
(3360 -1450);
DISPLAY 0.638298 (3360 -1450);
FORCEPROP 1 LAST TOLERANCE 1%
J 2
(3355 -1400);
DISPLAY 0.638298 (3355 -1400);
FORCEPROP 1 LAST VALUE 10K
J 2
(3355 -1350);
DISPLAY 0.638298 (3355 -1350);
FORCEPROP 1 LAST $LOCATION R3182
J 2
(3355 -1300);
DISPLAY 0.787234 (3355 -1300);
FORCEPROP 1 LASTPIN (3400 -1325) $PN 1
J 2
(3395 -1363);
DISPLAY 0.787234 (3395 -1363);
FORCEPROP 1 LASTPIN (3400 -1525) $PN 2
J 2
(3395 -1515);
DISPLAY 0.787234 (3395 -1515);
FORCEPROP 2 LAST CDS_LIB pure_quanta
J 2
(3400 -1425);
PAINT MONO (3400 -1425);
DISPLAY INVISIBLE (3400 -1425);
FORCEPROP 1 LAST PATH I6
J 2
(3350 -1250);
DISPLAY 0.978723 (3350 -1250);
PAINT WHITE (3350 -1250);
DISPLAY INVISIBLE (3350 -1250);
FORCEPROP 2 LAST CDS_LOCATION R3182
J 0
(3350 -1200);
DISPLAY 1.021277 (3350 -1200);
DISPLAY INVISIBLE (3350 -1200);
FORCEPROP 2 LAST $SEC 1
J 0
(3350 -1200);
DISPLAY 0.680851 (3350 -1200);
PAINT MONO (3350 -1200);
DISPLAY INVISIBLE (3350 -1200);
FORCEPROP 2 LAST CDS_SEC 1
J 0
(3350 -1200);
DISPLAY 1.021277 (3350 -1200);
DISPLAY INVISIBLE (3350 -1200);
FORCEADD UNIVERSAL_POWER..1
(9300 -1225);
FORCEPROP 3 LASTPIN (9300 -1275) SIG_NAME P3V3_AUX\g
J 0
(9310 -1265);
DISPLAY 0.659574 (9310 -1265);
PAINT MONO (9310 -1265);
DISPLAY INVISIBLE (9310 -1265);
FORCEPROP 1 LAST HDL_POWER P3V3_AUX
J 1
(9300 -1175);
DISPLAY 0.872340 (9300 -1175);
PAINT GREEN (9300 -1175);
FORCEPROP 1 LAST PATH I60
J 0
(9350 -1200);
DISPLAY 0.872340 (9350 -1200);
PAINT AQUA (9350 -1200);
DISPLAY INVISIBLE (9350 -1200);
FORCEPROP 2 LAST CDS_LIB logical_power
J 0
(9300 -1225);
DISPLAY INVISIBLE (9300 -1225);
FORCEADD 74LVC1G07GV..1
(8125 -1775);
FORCEPROP 1 LAST PART_NUMBER AL1G0007001
J 0
(8000 -1525);
DISPLAY 0.723404 (8000 -1525);
PAINT GREEN (8000 -1525);
DISPLAY INVISIBLE (8000 -1525);
FORCEPROP 2 LAST VALUE 74LVC1G07GV
J 0
(8000 -1350);
DISPLAY 0.638298 (8000 -1350);
FORCEPROP 2 LAST PART_TYPE SMLF
J 0
(8000 -1300);
DISPLAY 0.638298 (8000 -1300);
FORCEPROP 1 LAST MATERIAL IC
J 0
(8006 -1593);
DISPLAY 0.723404 (8006 -1593);
PAINT GREEN (8006 -1593);
FORCEPROP 1 LAST $LOCATION U219
J 0
(8000 -1450);
DISPLAY 0.723404 (8000 -1450);
PAINT GREEN (8000 -1450);
FORCEPROP 0 LASTPIN (7850 -1775) $PN 2
J 2
(7840 -1765);
DISPLAY 0.680851 (7840 -1765);
PAINT MONO (7840 -1765);
FORCEPROP 0 LASTPIN (7850 -1875) $PN 3
J 2
(7840 -1865);
DISPLAY 0.680851 (7840 -1865);
PAINT MONO (7840 -1865);
FORCEPROP 0 LASTPIN (7850 -1675) $PN 1
J 2
(7840 -1665);
DISPLAY 0.680851 (7840 -1665);
PAINT MONO (7840 -1665);
FORCEPROP 0 LASTPIN (8400 -1675) $PN 5
J 0
(8410 -1665);
DISPLAY 0.680851 (8410 -1665);
PAINT MONO (8410 -1665);
FORCEPROP 0 LASTPIN (8400 -1875) $PN 4
J 0
(8410 -1865);
DISPLAY 0.680851 (8410 -1865);
PAINT MONO (8410 -1865);
FORCEPROP 1 LAST PATH I61
J 0
(8125 -1775);
DISPLAY 0.723404 (8125 -1775);
PAINT GREEN (8125 -1775);
DISPLAY INVISIBLE (8125 -1775);
FORCEPROP 2 LAST CDS_LIB pure_quanta
J 0
(8125 -1775);
DISPLAY INVISIBLE (8125 -1775);
FORCEPROP 1 LAST CDS_LMAN_SYM_OUTLINE -125,150,125,-150
J 0
(8125 -1775);
DISPLAY 0.468085 (8125 -1775);
PAINT GREEN (8125 -1775);
DISPLAY INVISIBLE (8125 -1775);
FORCEPROP 1 LAST NEEDS_NO_SIZE TRUE
J 0
(8125 -1775);
DISPLAY 0.723404 (8125 -1775);
PAINT GREEN (8125 -1775);
DISPLAY INVISIBLE (8125 -1775);
FORCEPROP 0 LAST CDS_LOCATION U219
J 0
(8000 -1250);
DISPLAY 1.021277 (8000 -1250);
DISPLAY INVISIBLE (8000 -1250);
FORCEPROP 0 LAST $SEC 1
J 0
(8000 -1250);
DISPLAY 0.680851 (8000 -1250);
PAINT MONO (8000 -1250);
DISPLAY INVISIBLE (8000 -1250);
FORCEPROP 0 LAST CDS_SEC 1
J 0
(8000 -1250);
DISPLAY 1.021277 (8000 -1250);
DISPLAY INVISIBLE (8000 -1250);
FORCEADD UNIVERSAL_GND..1
(5700 -2975);
FORCEPROP 3 LASTPIN (5700 -2925) SIG_NAME GND\g
J 0
(5710 -2915);
DISPLAY 0.659574 (5710 -2915);
PAINT MONO (5710 -2915);
DISPLAY INVISIBLE (5710 -2915);
FORCEPROP 2 LAST CDS_LIB logical_power
J 0
(5700 -2975);
PAINT MONO (5700 -2975);
DISPLAY INVISIBLE (5700 -2975);
FORCEPROP 1 LAST HDL_POWER GND
J 1
(5725 -3050);
DISPLAY 0.872340 (5725 -3050);
PAINT GREEN (5725 -3050);
DISPLAY INVISIBLE (5725 -3050);
FORCEPROP 1 LAST PATH I64
J 0
(5775 -2975);
DISPLAY 0.872340 (5775 -2975);
PAINT AQUA (5775 -2975);
DISPLAY INVISIBLE (5775 -2975);
FORCEADD Q_CAP..1
R 2
(5700 -2750);
FORCEPROP 1 LAST PART_NUMBER CH4104K1B00
J 2
(5650 -2900);
DISPLAY 0.510638 (5650 -2900);
DISPLAY INVISIBLE (5650 -2900);
FORCEPROP 1 LAST VALUE 0.1UF
J 2
(5650 -2700);
DISPLAY 0.510638 (5650 -2700);
FORCEPROP 1 LAST VOLTAGE 25V
J 2
(5650 -2750);
DISPLAY 0.510638 (5650 -2750);
FORCEPROP 1 LAST MATERIAL X7R
J 2
(5650 -2850);
DISPLAY 0.510638 (5650 -2850);
FORCEPROP 1 LAST PACK_TYPE 0402
J 2
(5650 -2950);
DISPLAY 0.510638 (5650 -2950);
FORCEPROP 1 LAST TOLERANCE 10%
J 2
(5650 -2800);
DISPLAY 0.510638 (5650 -2800);
FORCEPROP 1 LAST $LOCATION C1841
J 2
(5650 -2650);
DISPLAY 0.978723 (5650 -2650);
FORCEPROP 1 LASTPIN (5700 -2650) $PN 1
J 2
(5690 -2670);
DISPLAY 0.787234 (5690 -2670);
FORCEPROP 1 LASTPIN (5700 -2850) $PN 2
J 2
(5690 -2870);
DISPLAY 0.787234 (5690 -2870);
FORCEPROP 2 LAST CDS_LIB pure_quanta
J 0
(5700 -2750);
PAINT MONO (5700 -2750);
DISPLAY INVISIBLE (5700 -2750);
FORCEPROP 1 LAST PATH I65
J 2
(5650 -2600);
DISPLAY 0.978723 (5650 -2600);
PAINT WHITE (5650 -2600);
DISPLAY INVISIBLE (5650 -2600);
FORCEPROP 2 LAST CDS_LOCATION C1841
J 0
(5650 -2550);
DISPLAY 1.021277 (5650 -2550);
DISPLAY INVISIBLE (5650 -2550);
FORCEPROP 2 LAST $SEC 1
J 0
(5650 -2550);
DISPLAY 0.680851 (5650 -2550);
PAINT MONO (5650 -2550);
DISPLAY INVISIBLE (5650 -2550);
FORCEPROP 2 LAST CDS_SEC 1
J 0
(5650 -2550);
DISPLAY 1.021277 (5650 -2550);
DISPLAY INVISIBLE (5650 -2550);
FORCEADD UNIVERSAL_POWER..1
(5700 -2450);
FORCEPROP 3 LASTPIN (5700 -2500) SIG_NAME P3V3_AUX\g
J 0
(5710 -2490);
DISPLAY 0.659574 (5710 -2490);
PAINT MONO (5710 -2490);
DISPLAY INVISIBLE (5710 -2490);
FORCEPROP 1 LAST HDL_POWER P3V3_AUX
J 1
(5700 -2400);
DISPLAY 0.872340 (5700 -2400);
PAINT GREEN (5700 -2400);
FORCEPROP 2 LAST CDS_LIB logical_power
J 0
(5700 -2450);
PAINT MONO (5700 -2450);
DISPLAY INVISIBLE (5700 -2450);
FORCEPROP 1 LAST PATH I69
J 0
(5750 -2425);
DISPLAY 0.872340 (5750 -2425);
PAINT AQUA (5750 -2425);
DISPLAY INVISIBLE (5750 -2425);
FORCEADD Q_RES..2
(3675 -1425);
FORCEPROP 1 LAST PART_NUMBER CS31002FB08
J 0
(3715 -1550);
DISPLAY 0.638298 (3715 -1550);
DISPLAY INVISIBLE (3715 -1550);
FORCEPROP 1 LAST MATERIAL CHIP
J 0
(3715 -1500);
DISPLAY 0.638298 (3715 -1500);
FORCEPROP 1 LAST WATTAGE 1/16W
J 0
(3715 -1450);
DISPLAY 0.638298 (3715 -1450);
FORCEPROP 1 LAST VALUE 10K
J 0
(3720 -1350);
DISPLAY 0.638298 (3720 -1350);
FORCEPROP 1 LAST TOLERANCE 1%
J 0
(3720 -1400);
DISPLAY 0.638298 (3720 -1400);
FORCEPROP 1 LAST PACK_TYPE 0402LF
J 0
(3715 -1600);
DISPLAY 0.638298 (3715 -1600);
FORCEPROP 1 LAST $LOCATION R3183
J 0
(3720 -1300);
DISPLAY 0.808511 (3720 -1300);
FORCEPROP 1 LASTPIN (3675 -1325) $PN 1
J 0
(3680 -1363);
DISPLAY 0.787234 (3680 -1363);
FORCEPROP 1 LASTPIN (3675 -1525) $PN 2
J 0
(3680 -1515);
DISPLAY 0.787234 (3680 -1515);
FORCEPROP 2 LAST CDS_LIB pure_quanta
J 0
(3675 -1425);
PAINT MONO (3675 -1425);
DISPLAY INVISIBLE (3675 -1425);
FORCEPROP 1 LAST PATH I7
J 0
(3725 -1250);
DISPLAY 0.978723 (3725 -1250);
PAINT WHITE (3725 -1250);
DISPLAY INVISIBLE (3725 -1250);
FORCEPROP 2 LAST CDS_LOCATION R3183
J 2
(3725 -1200);
DISPLAY 1.021277 (3725 -1200);
DISPLAY INVISIBLE (3725 -1200);
FORCEPROP 2 LAST $SEC 1
J 2
(3725 -1200);
DISPLAY 0.680851 (3725 -1200);
PAINT MONO (3725 -1200);
DISPLAY INVISIBLE (3725 -1200);
FORCEPROP 2 LAST CDS_SEC 1
J 2
(3725 -1200);
DISPLAY 1.021277 (3725 -1200);
DISPLAY INVISIBLE (3725 -1200);
FORCEADD Q_RES..1
(7150 -3175);
FORCEPROP 1 LAST PART_NUMBER CS00002JB13
J 0
(7050 -3125);
DISPLAY 0.510638 (7050 -3125);
DISPLAY INVISIBLE (7050 -3125);
FORCEPROP 1 LAST VALUE 0
J 2
(7275 -3175);
DISPLAY 0.510638 (7275 -3175);
FORCEPROP 1 LAST PACK_TYPE 0402LF
J 0
(7050 -3075);
DISPLAY 0.510638 (7050 -3075);
FORCEPROP 1 LAST MATERIAL CHIP
J 0
(7375 -3175);
DISPLAY 0.510638 (7375 -3175);
FORCEPROP 1 LAST TOLERANCE 5%
J 0
(7300 -3175);
DISPLAY 0.510638 (7300 -3175);
FORCEPROP 1 LAST WATTAGE 1/16W
J 2
(7400 -3075);
DISPLAY 0.510638 (7400 -3075);
FORCEPROP 1 LAST $LOCATION R3236
J 0
(6925 -3175);
DISPLAY 0.787234 (6925 -3175);
FORCEPROP 1 LASTPIN (7050 -3175) $PN 1
J 0
(7062 -3163);
DISPLAY 0.787234 (7062 -3163);
PAINT MONO (7062 -3163);
FORCEPROP 1 LASTPIN (7250 -3175) $PN 2
J 0
(7212 -3163);
DISPLAY 0.787234 (7212 -3163);
PAINT MONO (7212 -3163);
FORCEPROP 2 LAST CDS_LIB pure_quanta
J 0
(7150 -3175);
DISPLAY INVISIBLE (7150 -3175);
FORCEPROP 1 LAST PATH I70
J 0
(7100 -3025);
DISPLAY 0.978723 (7100 -3025);
PAINT WHITE (7100 -3025);
DISPLAY INVISIBLE (7100 -3025);
FORCEPROP 0 LAST CDS_LOCATION R3236
J 0
(7400 -3050);
DISPLAY 1.021277 (7400 -3050);
DISPLAY INVISIBLE (7400 -3050);
FORCEPROP 0 LAST $SEC 1
J 0
(7400 -3050);
DISPLAY 0.680851 (7400 -3050);
PAINT MONO (7400 -3050);
DISPLAY INVISIBLE (7400 -3050);
FORCEPROP 0 LAST CDS_SEC 1
J 0
(7400 -3050);
DISPLAY 1.021277 (7400 -3050);
DISPLAY INVISIBLE (7400 -3050);
FORCEADD UNIVERSAL_GND..1
(6875 -3600);
FORCEPROP 3 LASTPIN (6875 -3550) SIG_NAME GND\g
J 0
(6885 -3540);
DISPLAY 0.659574 (6885 -3540);
PAINT MONO (6885 -3540);
DISPLAY INVISIBLE (6885 -3540);
FORCEPROP 2 LAST CDS_LIB logical_power
J 0
(6875 -3600);
PAINT MONO (6875 -3600);
DISPLAY INVISIBLE (6875 -3600);
FORCEPROP 1 LAST HDL_POWER GND
J 1
(6900 -3675);
DISPLAY 0.872340 (6900 -3675);
PAINT GREEN (6900 -3675);
DISPLAY INVISIBLE (6900 -3675);
FORCEPROP 1 LAST PATH I71
J 0
(6950 -3600);
DISPLAY 0.872340 (6950 -3600);
PAINT AQUA (6950 -3600);
DISPLAY INVISIBLE (6950 -3600);
FORCEADD Q_RES..2
(6875 -3375);
FORCEPROP 1 LAST PART_NUMBER CS41002FB09
J 0
(6915 -3500);
DISPLAY 0.638298 (6915 -3500);
DISPLAY INVISIBLE (6915 -3500);
FORCEPROP 1 LAST TOLERANCE 1%
J 0
(6920 -3350);
DISPLAY 0.638298 (6920 -3350);
FORCEPROP 1 LAST WATTAGE 1/16W
J 0
(6915 -3400);
DISPLAY 0.638298 (6915 -3400);
FORCEPROP 1 LAST MATERIAL CHIP
J 0
(6915 -3450);
DISPLAY 0.638298 (6915 -3450);
FORCEPROP 1 LAST PACK_TYPE 0402LF
J 0
(6915 -3550);
DISPLAY 0.638298 (6915 -3550);
FORCEPROP 1 LAST VALUE 100K
J 0
(6920 -3300);
DISPLAY 0.638298 (6920 -3300);
FORCEPROP 1 LAST $LOCATION R3235
J 0
(6920 -3250);
DISPLAY 0.787234 (6920 -3250);
FORCEPROP 1 LASTPIN (6875 -3275) $PN 1
J 0
(6880 -3313);
DISPLAY 0.787234 (6880 -3313);
FORCEPROP 1 LASTPIN (6875 -3475) $PN 2
J 0
(6880 -3465);
DISPLAY 0.787234 (6880 -3465);
FORCEPROP 2 LAST CDS_LIB pure_quanta
J 0
(6875 -3375);
PAINT MONO (6875 -3375);
DISPLAY INVISIBLE (6875 -3375);
FORCEPROP 1 LAST PATH I72
J 0
(6925 -3200);
DISPLAY 0.978723 (6925 -3200);
PAINT WHITE (6925 -3200);
DISPLAY INVISIBLE (6925 -3200);
FORCEPROP 2 LAST CDS_LOCATION R3235
J 0
(6925 -3150);
DISPLAY 1.021277 (6925 -3150);
DISPLAY INVISIBLE (6925 -3150);
FORCEPROP 2 LAST $SEC 1
J 0
(6925 -3150);
DISPLAY 0.680851 (6925 -3150);
PAINT MONO (6925 -3150);
DISPLAY INVISIBLE (6925 -3150);
FORCEPROP 2 LAST CDS_SEC 1
J 0
(6925 -3150);
DISPLAY 1.021277 (6925 -3150);
DISPLAY INVISIBLE (6925 -3150);
FORCEADD OFFPAGE..2
(8125 -3175);
FORCEPROP 2 LAST $XR0 159 
J 0
(8314 -3175);
DISPLAY 0.638298 (8314 -3175);
PAINT MONO (8314 -3175);
FORCEPROP 2 LAST CDS_LIB standard
J 0
(8125 -3175);
DISPLAY INVISIBLE (8125 -3175);
FORCEPROP 2 LAST PATH I73
J 0
(8300 -3100);
DISPLAY 1.021277 (8300 -3100);
DISPLAY INVISIBLE (8300 -3100);
FORCEPROP 1 LAST OFFPAGE TRUE
J 0
(8450 -3300);
DISPLAY 0.872340 (8450 -3300);
PAINT GREEN (8450 -3300);
DISPLAY INVISIBLE (8450 -3300);
FORCEPROP 1 LAST COMMENT_BODY TRUE
J 0
(8080 -3270);
DISPLAY 0.872340 (8080 -3270);
PAINT GREEN (8080 -3270);
DISPLAY INVISIBLE (8080 -3270);
FORCEADD 74LVC1G126SE7..1
(5925 -3175);
FORCEPROP 1 LAST PART_NUMBER AL1G0126009
J 0
(6031 -3491);
DISPLAY 0.723404 (6031 -3491);
PAINT GREEN (6031 -3491);
DISPLAY INVISIBLE (6031 -3491);
FORCEPROP 2 LAST VALUE 74LVC1G126SE-7
J 0
(6050 -3050);
DISPLAY 0.638298 (6050 -3050);
FORCEPROP 2 LAST PART_TYPE SMLF
J 0
(6050 -3000);
DISPLAY 0.638298 (6050 -3000);
FORCEPROP 1 LAST MATERIAL IC
J 0
(6031 -3618);
DISPLAY 0.723404 (6031 -3618);
PAINT GREEN (6031 -3618);
FORCEPROP 1 LAST LOCATION U225
J 0
(6031 -3344);
DISPLAY 0.723404 (6031 -3344);
PAINT GREEN (6031 -3344);
FORCEPROP 0 LASTPIN (5675 -3125) $PN 2
J 2
(5665 -3115);
DISPLAY 0.680851 (5665 -3115);
PAINT MONO (5665 -3115);
FORCEPROP 0 LASTPIN (5925 -3425) $PN 3
R 1
J 2
(5915 -3435);
DISPLAY 0.680851 (5915 -3435);
PAINT MONO (5915 -3435);
FORCEPROP 0 LASTPIN (5675 -3225) $PN 1
J 2
(5665 -3215);
DISPLAY 0.680851 (5665 -3215);
PAINT MONO (5665 -3215);
FORCEPROP 0 LASTPIN (5925 -2925) $PN 5
R 1
J 0
(5915 -2915);
DISPLAY 0.680851 (5915 -2915);
PAINT MONO (5915 -2915);
FORCEPROP 0 LASTPIN (6175 -3175) $PN 4
J 0
(6185 -3165);
DISPLAY 0.680851 (6185 -3165);
PAINT MONO (6185 -3165);
FORCEPROP 1 LAST NEEDS_NO_SIZE TRUE
J 0
(5925 -3175);
DISPLAY 0.723404 (5925 -3175);
PAINT GREEN (5925 -3175);
DISPLAY INVISIBLE (5925 -3175);
FORCEPROP 1 LAST PATH I74
J 0
(5925 -3175);
DISPLAY 0.723404 (5925 -3175);
PAINT GREEN (5925 -3175);
DISPLAY INVISIBLE (5925 -3175);
FORCEPROP 2 LAST CDS_LIB pure_quanta
J 0
(5925 -3175);
DISPLAY INVISIBLE (5925 -3175);
FORCEPROP 1 LAST CDS_LMAN_SYM_OUTLINE -100,100,100,-100
J 0
(5925 -3175);
DISPLAY 0.468085 (5925 -3175);
PAINT GREEN (5925 -3175);
DISPLAY INVISIBLE (5925 -3175);
FORCEPROP 0 LAST $SEC 1
J 0
(6050 -2950);
DISPLAY 0.680851 (6050 -2950);
PAINT MONO (6050 -2950);
DISPLAY INVISIBLE (6050 -2950);
FORCEPROP 0 LAST CDS_SEC 1
J 0
(6050 -2950);
DISPLAY 1.021277 (6050 -2950);
DISPLAY INVISIBLE (6050 -2950);
FORCEADD Q_RES..1
(4350 -3225);
FORCEPROP 1 LAST PART_NUMBER CS03322FB03
J 0
(4250 -3400);
DISPLAY 0.510638 (4250 -3400);
DISPLAY INVISIBLE (4250 -3400);
FORCEPROP 1 LAST PACK_TYPE 0402LF
J 0
(4250 -3300);
DISPLAY 0.510638 (4250 -3300);
FORCEPROP 1 LAST WATTAGE 1/16W
J 2
(4525 -3350);
DISPLAY 0.510638 (4525 -3350);
FORCEPROP 1 LAST MATERIAL CHIP
J 0
(4250 -3350);
DISPLAY 0.510638 (4250 -3350);
FORCEPROP 1 LAST VALUE 33.2
J 2
(4550 -3225);
DISPLAY 0.510638 (4550 -3225);
FORCEPROP 1 LAST TOLERANCE 1%
J 0
(4575 -3225);
DISPLAY 0.510638 (4575 -3225);
FORCEPROP 1 LAST $LOCATION R3234
J 0
(4100 -3225);
DISPLAY 0.638298 (4100 -3225);
FORCEPROP 1 LASTPIN (4250 -3225) $PN 1
J 0
(4262 -3213);
DISPLAY 0.787234 (4262 -3213);
FORCEPROP 1 LASTPIN (4450 -3225) $PN 2
J 0
(4412 -3213);
DISPLAY 0.787234 (4412 -3213);
FORCEPROP 1 LAST PATH I75
J 0
(4300 -3075);
DISPLAY 0.978723 (4300 -3075);
PAINT WHITE (4300 -3075);
DISPLAY INVISIBLE (4300 -3075);
FORCEPROP 2 LAST CDS_LIB pure_quanta
J 0
(4350 -3225);
PAINT MONO (4350 -3225);
DISPLAY INVISIBLE (4350 -3225);
FORCEPROP 2 LAST CDS_LOCATION R3234
J 0
(4300 -3025);
DISPLAY 1.021277 (4300 -3025);
DISPLAY INVISIBLE (4300 -3025);
FORCEPROP 2 LAST $SEC 1
J 0
(4300 -3025);
DISPLAY 0.680851 (4300 -3025);
PAINT MONO (4300 -3025);
DISPLAY INVISIBLE (4300 -3025);
FORCEPROP 2 LAST CDS_SEC 1
J 0
(4300 -3025);
DISPLAY 1.021277 (4300 -3025);
DISPLAY INVISIBLE (4300 -3025);
FORCEADD OFFPAGE..1
(3125 -3225);
FORCEPROP 2 LAST $XR2 160 
J 0
(2633 -3225);
DISPLAY 0.638298 (2633 -3225);
PAINT MONO (2633 -3225);
FORCEPROP 2 LAST $XR1 164 
J 0
(2753 -3225);
DISPLAY 0.638298 (2753 -3225);
PAINT MONO (2753 -3225);
FORCEPROP 2 LAST $XR0 159 
J 0
(2873 -3225);
DISPLAY 0.638298 (2873 -3225);
PAINT MONO (2873 -3225);
FORCEPROP 2 LAST PATH I76
J 0
(2875 -3175);
DISPLAY 1.021277 (2875 -3175);
DISPLAY INVISIBLE (2875 -3175);
FORCEPROP 1 LAST OFFPAGE TRUE
J 0
(3450 -3350);
DISPLAY 0.872340 (3450 -3350);
PAINT GREEN (3450 -3350);
DISPLAY INVISIBLE (3450 -3350);
FORCEPROP 1 LAST COMMENT_BODY TRUE
J 0
(3250 -3325);
DISPLAY 0.872340 (3250 -3325);
PAINT GREEN (3250 -3325);
DISPLAY INVISIBLE (3250 -3325);
FORCEPROP 2 LAST CDS_LIB standard
J 0
(3125 -3225);
PAINT MONO (3125 -3225);
DISPLAY INVISIBLE (3125 -3225);
FORCEADD OFFPAGE..1
(4550 -3125);
FORCEPROP 2 LAST $XR7 245 
J 0
(3428 -3125);
DISPLAY 0.638298 (3428 -3125);
PAINT MONO (3428 -3125);
FORCEPROP 2 LAST $XR6 236 
J 0
(3548 -3125);
DISPLAY 0.638298 (3548 -3125);
PAINT MONO (3548 -3125);
FORCEPROP 2 LAST $XR5 233 
J 0
(3668 -3125);
DISPLAY 0.638298 (3668 -3125);
PAINT MONO (3668 -3125);
FORCEPROP 2 LAST $XR4 231 
J 0
(3788 -3125);
DISPLAY 0.638298 (3788 -3125);
PAINT MONO (3788 -3125);
FORCEPROP 2 LAST $XR3 227 
J 0
(3908 -3125);
DISPLAY 0.638298 (3908 -3125);
PAINT MONO (3908 -3125);
FORCEPROP 2 LAST $XR2 191 
J 0
(4028 -3125);
DISPLAY 0.638298 (4028 -3125);
PAINT MONO (4028 -3125);
FORCEPROP 2 LAST $XR1 154 
J 0
(4148 -3125);
DISPLAY 0.638298 (4148 -3125);
PAINT MONO (4148 -3125);
FORCEPROP 2 LAST $XR0 215 
J 0
(4268 -3125);
DISPLAY 0.638298 (4268 -3125);
PAINT MONO (4268 -3125);
FORCEPROP 2 LAST PATH I77
J 0
(4300 -3075);
DISPLAY 1.021277 (4300 -3075);
DISPLAY INVISIBLE (4300 -3075);
FORCEPROP 1 LAST OFFPAGE TRUE
J 0
(4875 -3250);
DISPLAY 0.872340 (4875 -3250);
PAINT GREEN (4875 -3250);
DISPLAY INVISIBLE (4875 -3250);
FORCEPROP 1 LAST COMMENT_BODY TRUE
J 0
(4675 -3225);
DISPLAY 0.872340 (4675 -3225);
PAINT GREEN (4675 -3225);
DISPLAY INVISIBLE (4675 -3225);
FORCEPROP 2 LAST CDS_LIB standard
J 0
(4550 -3125);
PAINT MONO (4550 -3125);
DISPLAY INVISIBLE (4550 -3125);
FORCEADD UNIVERSAL_GND..1
(5925 -3550);
FORCEPROP 3 LASTPIN (5925 -3500) SIG_NAME GND\g
J 0
(5935 -3490);
DISPLAY 0.659574 (5935 -3490);
PAINT MONO (5935 -3490);
DISPLAY INVISIBLE (5935 -3490);
FORCEPROP 1 LAST PATH I78
J 0
(6000 -3550);
DISPLAY 0.872340 (6000 -3550);
PAINT AQUA (6000 -3550);
DISPLAY INVISIBLE (6000 -3550);
FORCEPROP 1 LAST HDL_POWER GND
J 1
(5950 -3625);
DISPLAY 0.872340 (5950 -3625);
PAINT GREEN (5950 -3625);
DISPLAY INVISIBLE (5950 -3625);
FORCEPROP 2 LAST CDS_LIB logical_power
J 0
(5925 -3550);
PAINT MONO (5925 -3550);
DISPLAY INVISIBLE (5925 -3550);
FORCEADD 74LVC1G126SE7..1
(4900 -1775);
FORCEPROP 1 LAST PART_NUMBER AL1G0126009
J 0
(4981 -2066);
DISPLAY 0.723404 (4981 -2066);
PAINT GREEN (4981 -2066);
DISPLAY INVISIBLE (4981 -2066);
FORCEPROP 2 LAST PART_TYPE SMLF
J 0
(5025 -1600);
DISPLAY 0.638298 (5025 -1600);
FORCEPROP 2 LAST VALUE 74LVC1G126SE-7
J 0
(4925 -1625);
DISPLAY 0.638298 (4925 -1625);
FORCEPROP 1 LAST MATERIAL IC
J 0
(4975 -2125);
DISPLAY 0.723404 (4975 -2125);
PAINT GREEN (4975 -2125);
FORCEPROP 1 LAST LOCATION U217
J 0
(5006 -1944);
DISPLAY 0.723404 (5006 -1944);
PAINT GREEN (5006 -1944);
FORCEPROP 0 LASTPIN (4650 -1725) $PN 2
J 2
(4640 -1715);
DISPLAY 0.680851 (4640 -1715);
PAINT MONO (4640 -1715);
FORCEPROP 0 LASTPIN (4900 -2025) $PN 3
R 1
J 2
(4890 -2035);
DISPLAY 0.680851 (4890 -2035);
PAINT MONO (4890 -2035);
FORCEPROP 0 LASTPIN (4650 -1825) $PN 1
J 2
(4640 -1815);
DISPLAY 0.680851 (4640 -1815);
PAINT MONO (4640 -1815);
FORCEPROP 0 LASTPIN (4900 -1525) $PN 5
R 1
J 0
(4890 -1515);
DISPLAY 0.680851 (4890 -1515);
PAINT MONO (4890 -1515);
FORCEPROP 0 LASTPIN (5150 -1775) $PN 4
J 0
(5160 -1765);
DISPLAY 0.680851 (5160 -1765);
PAINT MONO (5160 -1765);
FORCEPROP 1 LAST NEEDS_NO_SIZE TRUE
J 0
(4900 -1775);
DISPLAY 0.723404 (4900 -1775);
PAINT GREEN (4900 -1775);
DISPLAY INVISIBLE (4900 -1775);
FORCEPROP 1 LAST CDS_LMAN_SYM_OUTLINE -100,100,100,-100
J 0
(4900 -1775);
DISPLAY 0.468085 (4900 -1775);
PAINT GREEN (4900 -1775);
DISPLAY INVISIBLE (4900 -1775);
FORCEPROP 1 LAST PATH I79
J 0
(4900 -1775);
DISPLAY 0.723404 (4900 -1775);
PAINT GREEN (4900 -1775);
DISPLAY INVISIBLE (4900 -1775);
FORCEPROP 2 LAST CDS_LIB pure_quanta
J 0
(4900 -1775);
DISPLAY INVISIBLE (4900 -1775);
FORCEPROP 0 LAST $SEC 1
J 0
(5025 -1550);
DISPLAY 0.680851 (5025 -1550);
PAINT MONO (5025 -1550);
DISPLAY INVISIBLE (5025 -1550);
FORCEPROP 0 LAST CDS_SEC 1
J 0
(5025 -1550);
DISPLAY 1.021277 (5025 -1550);
DISPLAY INVISIBLE (5025 -1550);
FORCEADD UNIVERSAL_POWER..1
(3675 -1075);
FORCEPROP 3 LASTPIN (3675 -1125) SIG_NAME P3V3_OCP_V3_2\g
J 0
(3685 -1115);
DISPLAY 0.659574 (3685 -1115);
PAINT MONO (3685 -1115);
DISPLAY INVISIBLE (3685 -1115);
FORCEPROP 1 LAST HDL_POWER P3V3_OCP_V3_2
J 1
(3675 -1025);
DISPLAY 0.872340 (3675 -1025);
PAINT GREEN (3675 -1025);
FORCEPROP 2 LAST CDS_LIB logical_power
J 0
(3675 -1075);
PAINT MONO (3675 -1075);
DISPLAY INVISIBLE (3675 -1075);
FORCEPROP 1 LAST PATH I8
J 0
(3725 -1050);
DISPLAY 0.872340 (3725 -1050);
PAINT AQUA (3725 -1050);
DISPLAY INVISIBLE (3725 -1050);
FORCEADD UNIVERSAL_GND..1
(4900 -2225);
FORCEPROP 3 LASTPIN (4900 -2175) SIG_NAME GND\g
J 0
(4910 -2165);
DISPLAY 0.659574 (4910 -2165);
PAINT MONO (4910 -2165);
DISPLAY INVISIBLE (4910 -2165);
FORCEPROP 2 LAST CDS_LIB logical_power
J 0
(4900 -2225);
PAINT MONO (4900 -2225);
DISPLAY INVISIBLE (4900 -2225);
FORCEPROP 1 LAST HDL_POWER GND
J 1
(4925 -2300);
DISPLAY 0.872340 (4925 -2300);
PAINT GREEN (4925 -2300);
DISPLAY INVISIBLE (4925 -2300);
FORCEPROP 1 LAST PATH I80
J 0
(4975 -2225);
DISPLAY 0.872340 (4975 -2225);
PAINT AQUA (4975 -2225);
DISPLAY INVISIBLE (4975 -2225);
FORCEADD Q_CAP..1
(10825 -3200);
FORCEPROP 1 LAST PART_NUMBER CH4104K1B00
J 0
(10875 -3350);
DISPLAY 0.510638 (10875 -3350);
DISPLAY INVISIBLE (10875 -3350);
FORCEPROP 1 LAST PACK_TYPE 0402
J 0
(10875 -3400);
DISPLAY 0.510638 (10875 -3400);
FORCEPROP 1 LAST MATERIAL X7R
J 0
(10875 -3300);
DISPLAY 0.510638 (10875 -3300);
FORCEPROP 1 LAST TOLERANCE 10%
J 0
(10875 -3250);
DISPLAY 0.510638 (10875 -3250);
FORCEPROP 1 LAST VOLTAGE 25V
J 0
(10875 -3200);
DISPLAY 0.510638 (10875 -3200);
FORCEPROP 1 LAST VALUE 0.1UF
J 0
(10875 -3150);
DISPLAY 0.510638 (10875 -3150);
FORCEPROP 1 LAST $LOCATION C2345
J 0
(10875 -3100);
DISPLAY 0.978723 (10875 -3100);
FORCEPROP 1 LASTPIN (10825 -3100) $PN 1
J 0
(10835 -3120);
DISPLAY 0.787234 (10835 -3120);
PAINT MONO (10835 -3120);
FORCEPROP 1 LASTPIN (10825 -3300) $PN 2
J 0
(10835 -3320);
DISPLAY 0.787234 (10835 -3320);
PAINT MONO (10835 -3320);
FORCEPROP 1 LAST PATH I81
J 0
(10875 -3050);
DISPLAY 0.978723 (10875 -3050);
PAINT WHITE (10875 -3050);
DISPLAY INVISIBLE (10875 -3050);
FORCEPROP 2 LAST CDS_LIB pure_quanta
J 0
(10825 -3200);
DISPLAY INVISIBLE (10825 -3200);
FORCEPROP 0 LAST CDS_LOCATION C2345
J 0
(10875 -3050);
DISPLAY 1.021277 (10875 -3050);
DISPLAY INVISIBLE (10875 -3050);
FORCEPROP 0 LAST $SEC 1
J 0
(10875 -3050);
DISPLAY 0.680851 (10875 -3050);
PAINT MONO (10875 -3050);
DISPLAY INVISIBLE (10875 -3050);
FORCEPROP 0 LAST CDS_SEC 1
J 0
(10875 -3050);
DISPLAY 1.021277 (10875 -3050);
DISPLAY INVISIBLE (10875 -3050);
FORCEADD UNIVERSAL_POWER..1
(10625 -2925);
FORCEPROP 3 LASTPIN (10625 -2975) SIG_NAME P3V3_AUX\g
J 0
(10635 -2965);
DISPLAY 0.659574 (10635 -2965);
PAINT MONO (10635 -2965);
DISPLAY INVISIBLE (10635 -2965);
FORCEPROP 1 LAST HDL_POWER P3V3_AUX
J 1
(10625 -2875);
DISPLAY 0.872340 (10625 -2875);
PAINT GREEN (10625 -2875);
FORCEPROP 1 LAST PATH I82
J 0
(10675 -2900);
DISPLAY 0.872340 (10675 -2900);
PAINT AQUA (10675 -2900);
DISPLAY INVISIBLE (10675 -2900);
FORCEPROP 2 LAST CDS_LIB logical_power
J 0
(10625 -2925);
DISPLAY INVISIBLE (10625 -2925);
FORCEADD OFFPAGE..1
R 2
(11250 -3525);
FORCEPROP 2 LAST $XR0 160 
J 0
(11436 -3525);
DISPLAY 0.638298 (11436 -3525);
PAINT MONO (11436 -3525);
FORCEPROP 2 LAST PATH I83
J 0
(11425 -3450);
DISPLAY 1.021277 (11425 -3450);
DISPLAY INVISIBLE (11425 -3450);
FORCEPROP 2 LAST CDS_LIB standard
J 2
(11250 -3525);
DISPLAY INVISIBLE (11250 -3525);
FORCEPROP 1 LAST COMMENT_BODY TRUE
J 2
(11125 -3625);
DISPLAY 0.872340 (11125 -3625);
PAINT GREEN (11125 -3625);
DISPLAY INVISIBLE (11125 -3625);
FORCEPROP 1 LAST OFFPAGE TRUE
J 2
(10925 -3650);
DISPLAY 0.872340 (10925 -3650);
PAINT GREEN (10925 -3650);
DISPLAY INVISIBLE (10925 -3650);
FORCEADD UNIVERSAL_GND..1
(10825 -3425);
FORCEPROP 3 LASTPIN (10825 -3375) SIG_NAME GND\g
J 0
(10835 -3365);
DISPLAY 0.659574 (10835 -3365);
PAINT MONO (10835 -3365);
DISPLAY INVISIBLE (10835 -3365);
FORCEPROP 1 LAST PATH I84
J 0
(10900 -3425);
DISPLAY 0.872340 (10900 -3425);
PAINT AQUA (10900 -3425);
DISPLAY INVISIBLE (10900 -3425);
FORCEPROP 1 LAST HDL_POWER GND
J 1
(10850 -3500);
DISPLAY 0.872340 (10850 -3500);
PAINT GREEN (10850 -3500);
DISPLAY INVISIBLE (10850 -3500);
FORCEPROP 2 LAST CDS_LIB logical_power
J 0
(10825 -3425);
DISPLAY INVISIBLE (10825 -3425);
FORCEADD UNIVERSAL_GND..1
(9750 -3725);
FORCEPROP 3 LASTPIN (9750 -3675) SIG_NAME GND\g
J 0
(9760 -3665);
DISPLAY 0.659574 (9760 -3665);
PAINT MONO (9760 -3665);
DISPLAY INVISIBLE (9760 -3665);
FORCEPROP 1 LAST PATH I86
J 0
(9825 -3725);
DISPLAY 0.872340 (9825 -3725);
PAINT AQUA (9825 -3725);
DISPLAY INVISIBLE (9825 -3725);
FORCEPROP 1 LAST HDL_POWER GND
J 1
(9775 -3800);
DISPLAY 0.872340 (9775 -3800);
PAINT GREEN (9775 -3800);
DISPLAY INVISIBLE (9775 -3800);
FORCEPROP 2 LAST CDS_LIB logical_power
J 0
(9750 -3725);
DISPLAY INVISIBLE (9750 -3725);
FORCEADD OFFPAGE..1
(8775 -3375);
FORCEPROP 2 LAST $XR0 155 
J 0
(8523 -3375);
DISPLAY 0.638298 (8523 -3375);
PAINT MONO (8523 -3375);
FORCEPROP 2 LAST PATH I87
J 0
(8825 -3300);
DISPLAY 1.021277 (8825 -3300);
DISPLAY INVISIBLE (8825 -3300);
FORCEPROP 1 LAST OFFPAGE TRUE
J 0
(9100 -3500);
DISPLAY 0.872340 (9100 -3500);
PAINT GREEN (9100 -3500);
DISPLAY INVISIBLE (9100 -3500);
FORCEPROP 1 LAST COMMENT_BODY TRUE
J 0
(8900 -3475);
DISPLAY 0.872340 (8900 -3475);
PAINT GREEN (8900 -3475);
DISPLAY INVISIBLE (8900 -3475);
FORCEPROP 2 LAST CDS_LIB standard
J 0
(8775 -3375);
DISPLAY INVISIBLE (8775 -3375);
FORCEADD OFFPAGE..1
(4375 -450);
FORCEPROP 2 LAST $XR2 220 
J 0
(3883 -450);
DISPLAY 0.638298 (3883 -450);
PAINT MONO (3883 -450);
FORCEPROP 2 LAST $XR1 155 
J 0
(4003 -450);
DISPLAY 0.638298 (4003 -450);
PAINT MONO (4003 -450);
FORCEPROP 2 LAST $XR0 215 
J 0
(4123 -450);
DISPLAY 0.638298 (4123 -450);
PAINT MONO (4123 -450);
FORCEPROP 1 LAST COMMENT_BODY TRUE
J 0
(4500 -550);
DISPLAY 0.872340 (4500 -550);
PAINT GREEN (4500 -550);
DISPLAY INVISIBLE (4500 -550);
FORCEPROP 1 LAST OFFPAGE TRUE
J 0
(4700 -575);
DISPLAY 0.872340 (4700 -575);
PAINT GREEN (4700 -575);
DISPLAY INVISIBLE (4700 -575);
FORCEPROP 2 LAST CDS_LIB standard
J 0
(4375 -450);
PAINT MONO (4375 -450);
DISPLAY INVISIBLE (4375 -450);
FORCEPROP 2 LAST PATH I9
J 0
(4125 -400);
DISPLAY 1.021277 (4125 -400);
DISPLAY INVISIBLE (4125 -400);
FORCEADD Q_RES..1
(8625 -3475);
FORCEPROP 1 LAST PART_NUMBER CS00002JB13
J 0
(8525 -3425);
DISPLAY 0.510638 (8525 -3425);
DISPLAY INVISIBLE (8525 -3425);
FORCEPROP 1 LAST MATERIAL CHIP
J 0
(8850 -3475);
DISPLAY 0.510638 (8850 -3475);
FORCEPROP 1 LAST VALUE 0
J 2
(8750 -3475);
DISPLAY 0.510638 (8750 -3475);
FORCEPROP 1 LAST $LOCATION R4602
J 0
(8400 -3475);
DISPLAY 0.787234 (8400 -3475);
FORCEPROP 1 LASTPIN (8525 -3475) $PN 1
J 0
(8537 -3463);
DISPLAY 0.787234 (8537 -3463);
PAINT MONO (8537 -3463);
FORCEPROP 1 LASTPIN (8725 -3475) $PN 2
J 0
(8687 -3463);
DISPLAY 0.787234 (8687 -3463);
PAINT MONO (8687 -3463);
FORCEPROP 2 LAST CDS_LIB pure_quanta
J 0
(8625 -3475);
DISPLAY INVISIBLE (8625 -3475);
FORCEPROP 1 LAST PATH I90
J 0
(8575 -3325);
DISPLAY 0.978723 (8575 -3325);
PAINT WHITE (8575 -3325);
DISPLAY INVISIBLE (8575 -3325);
FORCEPROP 1 LAST PACK_TYPE 0402LF
J 0
(8525 -3375);
DISPLAY 0.510638 (8525 -3375);
DISPLAY INVISIBLE (8525 -3375);
FORCEPROP 1 LAST TOLERANCE 5%
J 0
(8775 -3475);
DISPLAY 0.510638 (8775 -3475);
DISPLAY INVISIBLE (8775 -3475);
FORCEPROP 1 LAST WATTAGE 1/16W
J 2
(8875 -3375);
DISPLAY 0.510638 (8875 -3375);
DISPLAY INVISIBLE (8875 -3375);
FORCEPROP 0 LAST CDS_LOCATION R4602
J 0
(8450 -3425);
DISPLAY 1.021277 (8450 -3425);
DISPLAY INVISIBLE (8450 -3425);
FORCEPROP 0 LAST $SEC 1
J 0
(8450 -3425);
DISPLAY 0.680851 (8450 -3425);
PAINT MONO (8450 -3425);
DISPLAY INVISIBLE (8450 -3425);
FORCEPROP 0 LAST CDS_SEC 1
J 0
(8450 -3425);
DISPLAY 1.021277 (8450 -3425);
DISPLAY INVISIBLE (8450 -3425);
FORCEADD OFFPAGE..2
R 2
(7575 -3475);
FORCEPROP 2 LAST $XR0 159 
J 0
(7290 -3475);
DISPLAY 0.638298 (7290 -3475);
PAINT MONO (7290 -3475);
FORCEPROP 2 LAST PATH I91
J 0
(7300 -3425);
DISPLAY 1.021277 (7300 -3425);
DISPLAY INVISIBLE (7300 -3425);
FORCEPROP 2 LAST CDS_LIB standard
J 2
(7575 -3475);
DISPLAY INVISIBLE (7575 -3475);
FORCEPROP 1 LAST OFFPAGE TRUE
J 2
(7250 -3600);
DISPLAY 0.872340 (7250 -3600);
PAINT GREEN (7250 -3600);
DISPLAY INVISIBLE (7250 -3600);
FORCEPROP 1 LAST COMMENT_BODY TRUE
J 2
(7620 -3570);
DISPLAY 0.872340 (7620 -3570);
PAINT GREEN (7620 -3570);
DISPLAY INVISIBLE (7620 -3570);
FORCEADD 74LVC1G66GV..1
(10175 -3475);
FORCEPROP 1 LAST PART_NUMBER AL001G66000
J 0
(10020 -3231);
DISPLAY 0.723404 (10020 -3231);
PAINT GREEN (10020 -3231);
DISPLAY INVISIBLE (10020 -3231);
FORCEPROP 1 LAST MATERIAL IC
J 0
(10020 -3320);
DISPLAY 0.723404 (10020 -3320);
PAINT GREEN (10020 -3320);
FORCEPROP 2 LAST PART_TYPE SMLF
J 0
(10025 -3050);
DISPLAY 1.021277 (10025 -3050);
FORCEPROP 2 LAST VALUE 74LVC1G66GV
J 0
(10025 -3100);
DISPLAY 1.021277 (10025 -3100);
FORCEPROP 1 LAST LOCATION U321
J 0
(10025 -3150);
DISPLAY 0.723404 (10025 -3150);
PAINT GREEN (10025 -3150);
FORCEPROP 0 LASTPIN (10475 -3525) $PN 4
J 0
(10485 -3515);
DISPLAY 0.680851 (10485 -3515);
PAINT MONO (10485 -3515);
FORCEPROP 0 LASTPIN (9875 -3575) $PN 3
J 2
(9865 -3565);
DISPLAY 0.680851 (9865 -3565);
PAINT MONO (9865 -3565);
FORCEPROP 0 LASTPIN (10475 -3375) $PN 5
J 0
(10485 -3365);
DISPLAY 0.680851 (10485 -3365);
PAINT MONO (10485 -3365);
FORCEPROP 0 LASTPIN (9875 -3375) $PN 1
J 2
(9865 -3365);
DISPLAY 0.680851 (9865 -3365);
PAINT MONO (9865 -3365);
FORCEPROP 0 LASTPIN (9875 -3475) $PN 2
J 2
(9865 -3465);
DISPLAY 0.680851 (9865 -3465);
PAINT MONO (9865 -3465);
FORCEPROP 1 LAST PIN_NAMES_ROTATE True
J 0
(10175 -3475);
DISPLAY 0.489362 (10175 -3475);
PAINT GREEN (10175 -3475);
DISPLAY INVISIBLE (10175 -3475);
FORCEPROP 1 LAST CDS_LMAN_SYM_OUTLINE -150,150,150,-150
J 0
(10175 -3475);
DISPLAY 0.468085 (10175 -3475);
PAINT GREEN (10175 -3475);
DISPLAY INVISIBLE (10175 -3475);
FORCEPROP 1 LAST PATH I92
J 0
(10325 -3625);
DISPLAY 0.723404 (10325 -3625);
PAINT GREEN (10325 -3625);
DISPLAY INVISIBLE (10325 -3625);
FORCEPROP 2 LAST CDS_LIB pure_quanta
J 0
(10175 -3475);
DISPLAY INVISIBLE (10175 -3475);
FORCEPROP 0 LAST $SEC 1
J 0
(10025 -3000);
DISPLAY 0.680851 (10025 -3000);
PAINT MONO (10025 -3000);
DISPLAY INVISIBLE (10025 -3000);
FORCEPROP 0 LAST CDS_SEC 1
J 0
(10025 -3000);
DISPLAY 1.021277 (10025 -3000);
DISPLAY INVISIBLE (10025 -3000);
FORCEADD QUANTA_TITLE_BLOCK_C..1
(11700 -4550);
FORCEPROP 0 LAST CDS_CON_LAST_MODIFIED Fri Aug 25 14:02:29 2023
J 0
(9815 -4535);
DISPLAY INVISIBLE (9815 -4535);
FORCEPROP 1 LAST CUSTOM_TXT_CDS <CON_LAST_MODIFIED>
J 0
(9815 -4535);
DISPLAY 0.978723 (9815 -4535);
FORCEPROP 2 LAST CUSTOM_TXT_CDS <XR_PAGE_TITLE>
J 0
(3810 700);
DISPLAY 0.638298 (3810 700);
PAINT PINK (3810 700);
DISPLAY INVISIBLE (3810 700);
FORCEPROP 1 LAST CUSTOM_TXT_CDS <NAME_2>
J 0
(8525 -4500);
FORCEPROP 1 LAST CUSTOM_TXT_CDS <NAME_1>
J 0
(8525 -4375);
FORCEPROP 1 LAST CUSTOM_TXT_CDS <Q_NUMBER>
J 0
(10297 -4447);
DISPLAY 1.212766 (10297 -4447);
FORCEPROP 1 LAST CUSTOM_TXT_CDS <Q_PROJ>
J 0
(9318 -4448);
DISPLAY 1.212766 (9318 -4448);
FORCEPROP 1 LAST CUSTOM_TXT_CDS <Q_REV>
J 0
(11516 -4447);
DISPLAY 1.212766 (11516 -4447);
FORCEPROP 1 LAST CUSTOM_TXT_CDS <CON_PAGE_NUM> OF <CON_TOTAL_PAGES>
J 0
(11254 -4532);
DISPLAY 0.978723 (11254 -4532);
FORCEPROP 1 LAST Q_TITLE PCIE - V3_2 OCP3.0 (3/3)
J 0
(2334 -4524);
DISPLAY 2.446809 (2334 -4524);
PAINT GREEN (2334 -4524);
FORCEPROP 1 LAST Q_DEPT 
J 1
(7937 -4501);
DISPLAY 1.957447 (7937 -4501);
PAINT GREEN (7937 -4501);
FORCEPROP 2 LAST CDS_XR_PAGE_TITLE CR-161 : @S9S_MB_2U_LIB.S9S_MB_2U(SCH_1):PAGE161
J 0
(3810 700);
DISPLAY 0.638298 (3810 700);
PAINT PINK (3810 700);
DISPLAY INVISIBLE (3810 700);
FORCEPROP 2 LAST CDS_LIB pure_quanta
J 0
(11700 -4550);
DISPLAY INVISIBLE (11700 -4550);
FORCEPROP 1 LAST CDS_LMAN_SYM_OUTLINE -9475,6775,100,-125
J 0
(11700 -4550);
DISPLAY 0.468085 (11700 -4550);
PAINT GREEN (11700 -4550);
DISPLAY INVISIBLE (11700 -4550);
FORCEPROP 1 LAST COMMENT_BODY TRUE
J 0
(11712 -4563);
DISPLAY 0.978723 (11712 -4563);
PAINT GREEN (11712 -4563);
DISPLAY INVISIBLE (11712 -4563);
FORCEPROP 2 LAST PAGE_BORDER TRUE
J 0
(3810 700);
DISPLAY 0.638298 (3810 700);
PAINT PINK (3810 700);
DISPLAY INVISIBLE (3810 700);
FORCEADD CAD_NOTE..1
(9950 -1200);
FORCEPROP 0 LAST S1 PLACE R2487 CLOSE TO U157
J 0
(9800 -1350);
DISPLAY 0.808511 (9800 -1350);
PAINT SKYBLUE (9800 -1350);
FORCEPROP 1 LAST COMMENT_BODY TRUE
J 0
(9975 -1100);
DISPLAY 0.978723 (9975 -1100);
DISPLAY INVISIBLE (9975 -1100);
FORCEPROP 2 LAST CDS_LIB logical_power
J 0
(9950 -1200);
DISPLAY INVISIBLE (9950 -1200);
FORCEADD DNS..2
(9300 -1450);
PAINT RED (9300 -1450);
FORCEPROP 1 LAST COMMENT_BODY TRUE
R 1
J 0
(9375 -1675);
DISPLAY 0.872340 (9375 -1675);
PAINT GREEN (9375 -1675);
DISPLAY INVISIBLE (9375 -1675);
FORCEPROP 2 LAST CDS_LIB mstr_misc
J 0
(9300 -1450);
DISPLAY INVISIBLE (9300 -1450);
WIRE 16 -1 (5200 -1075)(5200 -1000);
WIRE 16 -1 (4900 -1075)(5200 -1075);
WIRE 16 -1 (5200 -1175)(5200 -1075);
WIRE 16 -1 (6025 -1225)(6025 -1175);
WIRE 16 -1 (8550 -1275)(8550 -1325);
WIRE 16 -1 (10625 -2975)(10625 -3025);
WIRE 16 -1 (5250 1600)(5250 1650);
WIRE 16 -1 (5050 1600)(5250 1600);
WIRE 16 -1 (5250 1200)(5250 1600);
WIRE 16 -1 (7200 -75)(7200 -25);
WIRE 16 -1 (6300 150)(6300 100);
WIRE 16 -1 (9300 -1325)(9300 -1275);
WIRE 16 -1 (3675 -1200)(3675 -1125);
WIRE 16 -1 (3400 -1200)(3675 -1200);
WIRE 16 -1 (3675 -1325)(3675 -1200);
WIRE 16 -1 (5700 -2575)(5700 -2500);
WIRE 16 -1 (5925 -2575)(5700 -2575);
WIRE 16 -1 (5700 -2575)(5700 -2650);
WIRE 16 -1 (10825 -3300)(10825 -3375);
WIRE 16 -1 (9750 -3575)(9750 -3675);
WIRE 16 -1 (9875 -3575)(9750 -3575);
WIRE 16 -1 (5050 1325)(5050 1250);
WIRE 16 -1 (5350 -550)(5350 -725);
WIRE 16 -1 (5550 -550)(5350 -550);
WIRE 16 -1 (6500 -175)(6500 -250);
WIRE 16 -1 (5375 1000)(5375 900);
WIRE 16 -1 (8750 -1600)(8750 -1675);
WIRE 16 -1 (7650 -1875)(7650 -2050);
WIRE 16 -1 (7850 -1875)(7650 -1875);
WIRE 16 -1 (5200 -1375)(5200 -1450);
WIRE 16 -1 (4900 -2025)(4900 -2175);
WIRE 16 -1 (6875 -3475)(6875 -3550);
WIRE 16 -1 (5925 -3425)(5925 -3500);
WIRE 16 -1 (5700 -2850)(5700 -2925);
WIRE 16 -1 (4250 -3225)(3175 -3225);
FORCEPROP 0 LAST CDS_PHYS_NET_NAME OCP_V3_2_AUX_PWR_EN
J 0
(3540 -3183);
PAINT MONO (3540 -3183);
DISPLAY INVISIBLE (3540 -3183);
FORCEPROP 2 LAST SIG_NAME OCP_V3_2_AUX_PWR_EN
J 0
(3265 -3215);
DISPLAY 0.680851 (3265 -3215);
PAINT WHITE (3265 -3215);
WIRE 16 -1 (5675 -3225)(4450 -3225);
FORCEPROP 0 LAST CDS_PHYS_NET_NAME OCP_V3_2_AUX_PWR_EN_R3
J 0
(4815 -3183);
PAINT MONO (4815 -3183);
DISPLAY INVISIBLE (4815 -3183);
FORCEPROP 2 LAST SIG_NAME OCP_V3_2_AUX_PWR_EN_R3
J 0
(4740 -3215);
DISPLAY 0.680851 (4740 -3215);
PAINT WHITE (4740 -3215);
WIRE 16 -1 (5550 -450)(4425 -450);
FORCEPROP 0 LAST CDS_PHYS_NET_NAME FM_SYS_THROTTLE_R_N
J 0
(4450 -408);
PAINT MONO (4450 -408);
DISPLAY INVISIBLE (4450 -408);
FORCEPROP 0 LAST SIG_NAME FM_SYS_THROTTLE_R_N
J 0
(4650 -440);
DISPLAY 0.702128 (4650 -440);
PAINT WHITE (4650 -440);
WIRE 16 -1 (5550 -350)(4425 -350);
FORCEPROP 0 LAST CDS_PHYS_NET_NAME NC_U104_NC1
J 0
(4450 -308);
PAINT MONO (4450 -308);
DISPLAY INVISIBLE (4450 -308);
FORCEPROP 0 LAST SIG_NAME NC_U218_NC1
J 0
(4640 -340);
DISPLAY 0.702128 (4640 -340);
PAINT WHITE (4640 -340);
WIRE 16 -1 (7850 -1675)(7175 -1675);
FORCEPROP 0 LAST CDS_PHYS_NET_NAME NC_U157_NC1
J 0
(7200 -1633);
PAINT MONO (7200 -1633);
DISPLAY INVISIBLE (7200 -1633);
FORCEPROP 0 LAST SIG_NAME NC_U219_NC1
J 0
(7290 -1665);
DISPLAY 0.702128 (7290 -1665);
PAINT WHITE (7290 -1665);
WIRE 16 -1 (6100 -350)(6300 -350);
WIRE 16 -1 (6300 100)(6300 -350);
WIRE 16 -1 (6300 100)(6500 100);
WIRE 16 -1 (6500 100)(6500 25);
WIRE 16 2175 (7025 -400)(7675 -400);
WIRE 16 2175 (7675 150)(7675 -400);
WIRE 16 2175 (7025 150)(7025 -400);
WIRE 16 2175 (7025 150)(7675 150);
WIRE 16 -1 (7200 -550)(6100 -550);
FORCEPROP 0 LAST CDS_PHYS_NET_NAME OCP_SFF_PWRBRK_BUFF_N
J 0
(6615 -508);
PAINT MONO (6615 -508);
DISPLAY INVISIBLE (6615 -508);
FORCEPROP 2 LAST SIG_NAME OCP_V3_2_PWRBRK_BUFF_N
J 0
(6365 -540);
DISPLAY 0.680851 (6365 -540);
PAINT WHITE (6365 -540);
WIRE 16 -1 (7650 -550)(7200 -550);
WIRE 16 -1 (7200 -275)(7200 -550);
WIRE 16 -1 (7850 -1775)(6450 -1775);
FORCEPROP 0 LAST CDS_PHYS_NET_NAME OCP_SFF_WAKE_BUFF_R_N
J 0
(7115 -1733);
PAINT MONO (7115 -1733);
DISPLAY INVISIBLE (7115 -1733);
FORCEPROP 2 LAST SIG_NAME OCP_V3_2_WAKE_BUFF_R_N
J 0
(6940 -1765);
DISPLAY 0.680851 (6940 -1765);
PAINT WHITE (6940 -1765);
WIRE 16 -1 (7100 425)(8575 425);
FORCEPROP 0 LAST CDS_PHYS_NET_NAME RST_PERST3_OCP_SFF_N
J 0
(7125 467);
PAINT MONO (7125 467);
DISPLAY INVISIBLE (7125 467);
FORCEPROP 0 LAST SIG_NAME RST_PERST3_OCP_V3_2_N
J 0
(7675 435);
DISPLAY 0.702128 (7675 435);
PAINT WHITE (7675 435);
WIRE 16 -1 (9875 -3375)(8825 -3375);
FORCEPROP 0 LAST CDS_PHYS_NET_NAME CLK_50M_NCSI_OCP_SFF
J 0
(9190 -3341);
PAINT MONO (9190 -3341);
DISPLAY INVISIBLE (9190 -3341);
FORCEPROP 2 LAST SIG_NAME CLK_50M_NCSI_OCP_V3_2
J 0
(8990 -3365);
DISPLAY 0.510638 (8990 -3365);
PAINT WHITE (8990 -3365);
WIRE 16 -1 (9875 -3475)(8725 -3475);
FORCEPROP 0 LAST CDS_PHYS_NET_NAME CLK_50M_NCSI_OCP_SFF
J 0
(9090 -3441);
PAINT MONO (9090 -3441);
DISPLAY INVISIBLE (9090 -3441);
FORCEPROP 2 LAST SIG_NAME CLK_50M_NCSI_OCP_V3_2_ISO_R
J 0
(8990 -3465);
DISPLAY 0.510638 (8990 -3465);
PAINT WHITE (8990 -3465);
WIRE 16 -1 (11200 -3525)(10475 -3525);
FORCEPROP 2 LAST SIG_NAME FB_BMC_ISOLATE1
J 0
(10665 -3515);
DISPLAY 0.553191 (10665 -3515);
PAINT WHITE (10665 -3515);
WIRE 16 -1 (10825 -3025)(10825 -3100);
WIRE 16 -1 (10625 -3025)(10825 -3025);
WIRE 16 -1 (10625 -3025)(10625 -3375);
WIRE 16 -1 (10475 -3375)(10625 -3375);
WIRE 16 2175 (8325 -3425)(8975 -3425);
WIRE 16 2175 (8975 -3425)(8975 -3550);
WIRE 16 2175 (8325 -3425)(8325 -3550);
WIRE 16 2175 (8325 -3550)(8975 -3550);
WIRE 16 -1 (8525 -3475)(7625 -3475);
FORCEPROP 0 LAST CDS_PHYS_NET_NAME CLK_50M_NCSI_OCP_SFF
J 0
(7990 -3441);
PAINT MONO (7990 -3441);
DISPLAY INVISIBLE (7990 -3441);
FORCEPROP 2 LAST SIG_NAME CLK_50M_NCSI_OCP_V3_2_ISO
J 0
(7665 -3465);
DISPLAY 0.510638 (7665 -3465);
PAINT WHITE (7665 -3465);
WIRE 16 -1 (8750 -1325)(8750 -1400);
WIRE 16 -1 (8550 -1325)(8750 -1325);
WIRE 16 -1 (8550 -1325)(8550 -1675);
WIRE 16 -1 (8400 -1675)(8550 -1675);
WIRE 16 -1 (8075 -3175)(7250 -3175);
FORCEPROP 2 LAST SIG_NAME RST_SMB_OCP_V3_2_N
J 0
(7565 -3165);
DISPLAY 0.553191 (7565 -3165);
PAINT WHITE (7565 -3165);
WIRE 16 -1 (6175 -3175)(6875 -3175);
FORCEPROP 2 LAST SIG_NAME RST_HP_OCP_V3_2_R_N
J 0
(6340 -3165);
DISPLAY 0.553191 (6340 -3165);
PAINT WHITE (6340 -3165);
WIRE 16 -1 (7050 -3175)(6875 -3175);
WIRE 16 -1 (6875 -3275)(6875 -3175);
WIRE 16 -1 (5725 1100)(6625 1100);
FORCEPROP 0 LAST CDS_PHYS_NET_NAME RST_OCP_V3_1_BUF_N
J 0
(5725 1142);
PAINT MONO (5725 1142);
DISPLAY INVISIBLE (5725 1142);
FORCEPROP 0 LAST SIG_NAME RST_OCP_V3_2_BUF_N
J 0
(5875 1110);
DISPLAY 0.702128 (5875 1110);
PAINT WHITE (5875 1110);
WIRE 16 -1 (6625 1100)(6900 1100);
WIRE 16 -1 (6625 875)(6900 875);
WIRE 16 -1 (6625 1100)(6625 875);
WIRE 16 -1 (6625 875)(6625 650);
WIRE 16 -1 (6625 650)(6900 650);
WIRE 16 -1 (6625 650)(6625 425);
WIRE 16 -1 (6625 425)(6900 425);
WIRE 16 -1 (5375 1200)(5250 1200);
WIRE 16 -1 (5050 1600)(5050 1525);
WIRE 16 -1 (4900 -1525)(4900 -1075);
FORCEPROP 0 LAST VOLTAGE 3.3
J 0
(5000 -1525);
PAINT MONO (5000 -1525);
DISPLAY INVISIBLE (5000 -1525);
FORCEPROP 0 LAST CDS_PHYS_NET_NAME P3V3_AUX
J 0
(5000 -1478);
PAINT MONO (5000 -1478);
DISPLAY INVISIBLE (5000 -1478);
FORCEPROP 0 LAST $PHYS_NET_NAME P3V3_AUX
J 0
(5000 -1431);
PAINT MONO (5000 -1431);
DISPLAY INVISIBLE (5000 -1431);
WIRE 16 -1 (3400 -1325)(3400 -1200);
WIRE 16 -1 (5925 -2925)(5925 -2575);
WIRE 16 -1 (4600 -3125)(5675 -3125);
FORCEPROP 0 LAST CDS_PHYS_NET_NAME RST_SMB_SWITCH_N
J 0
(4965 -3083);
PAINT MONO (4965 -3083);
DISPLAY INVISIBLE (4965 -3083);
FORCEPROP 2 LAST SIG_NAME RST_SMB_SWITCH_N
J 0
(4740 -3115);
DISPLAY 0.680851 (4740 -3115);
PAINT WHITE (4740 -3115);
WIRE 16 -1 (3675 -1525)(3675 -1825);
WIRE 16 -1 (3675 -1825)(4650 -1825);
FORCEPROP 0 LAST CDS_PHYS_NET_NAME PU_OCP_SFF_WAKE_OE
J 0
(3915 -1783);
PAINT MONO (3915 -1783);
DISPLAY INVISIBLE (3915 -1783);
FORCEPROP 2 LAST SIG_NAME PU_OCP_V3_2_WAKE_OE
J 0
(3790 -1815);
DISPLAY 0.680851 (3790 -1815);
PAINT WHITE (3790 -1815);
WIRE 16 -1 (9700 -1875)(10750 -1875);
FORCEPROP 0 LAST CDS_PHYS_NET_NAME IRQ_LVC3_WAKE_N
J 0
(9725 -1833);
PAINT MONO (9725 -1833);
DISPLAY INVISIBLE (9725 -1833);
FORCEPROP 0 LAST SIG_NAME IRQ_LVC3_WAKE_N
J 0
(10065 -1865);
DISPLAY 0.702128 (10065 -1865);
PAINT WHITE (10065 -1865);
WIRE 16 -1 (9300 -1875)(9500 -1875);
WIRE 16 -1 (9300 -1525)(9300 -1875);
WIRE 16 -1 (8400 -1875)(9300 -1875);
FORCEPROP 0 LAST CDS_PHYS_NET_NAME IRQ_LVC3_WAKE_BUF_N
J 0
(8425 -1833);
PAINT MONO (8425 -1833);
DISPLAY INVISIBLE (8425 -1833);
FORCEPROP 0 LAST SIG_NAME IRQ_LVC3_V3_2_WAKE_BUF_N
J 0
(8490 -1865);
DISPLAY 0.702128 (8490 -1865);
PAINT WHITE (8490 -1865);
WIRE 16 -1 (6025 -1425)(6025 -1775);
WIRE 16 -1 (6250 -1775)(6025 -1775);
WIRE 16 -1 (5150 -1775)(6025 -1775);
FORCEPROP 0 LAST CDS_PHYS_NET_NAME OCP_SFF_WAKE_BUFF_N
J 0
(5515 -1733);
PAINT MONO (5515 -1733);
DISPLAY INVISIBLE (5515 -1733);
FORCEPROP 2 LAST SIG_NAME OCP_V3_2_WAKE_BUFF_N
J 0
(5290 -1765);
DISPLAY 0.680851 (5290 -1765);
PAINT WHITE (5290 -1765);
WIRE 16 -1 (3400 -1525)(3400 -1725);
WIRE 16 -1 (3400 -1725)(4650 -1725);
FORCEPROP 2 LAST SIG_NAME IRQ_LVC3_OCP_V3_2_WAKE_N
J 0
(3790 -1715);
DISPLAY 0.680851 (3790 -1715);
PAINT WHITE (3790 -1715);
WIRE 16 -1 (2925 -1725)(3400 -1725);
FORCEPROP 0 LAST CDS_PHYS_NET_NAME IRQ_LVC3_OCP_SFF_WAKE_N
J 0
(3390 -1683);
PAINT MONO (3390 -1683);
DISPLAY INVISIBLE (3390 -1683);
WIRE 16 -1 (4450 1100)(5375 1100);
FORCEPROP 0 LAST CDS_PHYS_NET_NAME RST_HP_OCP_V3_1_N
J 0
(4815 1142);
PAINT MONO (4815 1142);
DISPLAY INVISIBLE (4815 1142);
FORCEPROP 2 LAST SIG_NAME RST_HP_OCP_V3_2_N
J 0
(4590 1110);
DISPLAY 0.680851 (4590 1110);
PAINT WHITE (4590 1110);
WIRE 16 -1 (7100 1100)(8575 1100);
FORCEPROP 0 LAST CDS_PHYS_NET_NAME RST_PERST0_OCP_SFF_N
J 0
(7125 1142);
PAINT MONO (7125 1142);
DISPLAY INVISIBLE (7125 1142);
FORCEPROP 0 LAST SIG_NAME RST_PERST0_OCP_V3_2_N
J 0
(7675 1110);
DISPLAY 0.702128 (7675 1110);
PAINT WHITE (7675 1110);
WIRE 16 -1 (7100 875)(8575 875);
FORCEPROP 0 LAST CDS_PHYS_NET_NAME RST_PERST1_OCP_SFF_N
J 0
(7125 917);
PAINT MONO (7125 917);
DISPLAY INVISIBLE (7125 917);
FORCEPROP 0 LAST SIG_NAME RST_PERST1_OCP_V3_2_N
J 0
(7675 885);
DISPLAY 0.702128 (7675 885);
PAINT WHITE (7675 885);
WIRE 16 -1 (7100 650)(8575 650);
FORCEPROP 0 LAST CDS_PHYS_NET_NAME RST_PERST2_OCP_SFF_N
J 0
(7125 692);
PAINT MONO (7125 692);
DISPLAY INVISIBLE (7125 692);
FORCEPROP 0 LAST SIG_NAME RST_PERST2_OCP_V3_2_N
J 0
(7675 660);
DISPLAY 0.702128 (7675 660);
PAINT WHITE (7675 660);
WIRE 16 -1 (8950 -550)(7850 -550);
FORCEPROP 0 LAST CDS_PHYS_NET_NAME OCP_SFF_PWRBRK_N
J 0
(8390 -508);
PAINT MONO (8390 -508);
DISPLAY INVISIBLE (8390 -508);
FORCEPROP 2 LAST SIG_NAME OCP_V3_2_PWRBRK_N
J 0
(8265 -540);
DISPLAY 0.680851 (8265 -540);
PAINT WHITE (8265 -540);
DOT 1 (7200 -550);
DOT 1 (10625 -3025);
DOT 1 (6300 100);
DOT 1 (6625 1100);
DOT 1 (6625 875);
DOT 1 (6625 650);
DOT 1 (5250 1600);
DOT 1 (8550 -1325);
DOT 1 (9300 -1875);
DOT 1 (6025 -1775);
DOT 1 (5200 -1075);
DOT 1 (3675 -1200);
DOT 1 (3400 -1725);
DOT 1 (6875 -3175);
DOT 1 (5700 -2575);
FORCENOTE
20220120 ADD R4602
(8100 -3650) 0;
DISPLAY LEFT (8100 -3650);
DISPLAY 1.276596 (8100 -3650);
PAINT PINK (8100 -3650);
FORCENOTE
20210824 MODIFY FOR GT
(6250 1800) 0;
DISPLAY LEFT (6250 1800);
DISPLAY 2.510638 (6250 1800);
PAINT PINK (6250 1800);
QUIT
